G04 ================== begin FILE IDENTIFICATION RECORD ==================*
G04 Layout Name:  t6m_pdb_d_0928_1400_274.brd*
G04 Film Name:    bot.art*
G04 File Format:  Gerber RS274X*
G04 File Origin:  Cadence Allegro 16.3-S048*
G04 Origin Date:  Tue Nov 26 11:01:49 2013*
G04 *
G04 Layer:  DRAWING FORMAT/TITLE_BLOCK*
G04 Layer:  VIA CLASS/BOTTOM*
G04 Layer:  PIN/BOTTOM*
G04 Layer:  MANUFACTURING/PHOTOPLOT_OUTLINE*
G04 Layer:  ETCH/BOTTOM*
G04 Layer:  DRAWING FORMAT/TITLE_DATA_BOT*
G04 *
G04 Offset:    (0.00 0.00)*
G04 Mirror:    No*
G04 Mode:      Positive*
G04 Rotation:  0*
G04 FullContactRelief:  No*
G04 UndefLineWidth:     6.00*
G04 ================== end FILE IDENTIFICATION RECORD ====================*
%FSLAX25Y25*MOIN*%
%IR0*IPPOS*OFA0.00000B0.00000*MIA0B0*SFA1.00000B1.00000*%
%ADD11C,.02*%
%ADD26C,.03*%
%ADD19C,.04*%
%ADD17C,.06*%
%ADD14C,.052*%
%ADD24C,.026*%
%ADD33C,.046*%
%ADD29C,.064*%
%ADD10C,.055*%
%ADD21R,.04X.04*%
%ADD28C,.039*%
%ADD16C,.093*%
%ADD18R,.06X.06*%
%ADD23C,.077*%
%ADD22R,.052X.052*%
%ADD20C,.095*%
%ADD32R,.046X.046*%
%ADD30R,.064X.064*%
%ADD13R,.055X.055*%
%ADD31C,.099*%
%ADD25R,.077X.077*%
%ADD35O,.205X.244*%
%ADD12C,.132*%
%ADD34C,.205*%
%ADD36C,.315*%
%ADD15C,.126*%
%ADD27C,.158*%
%ADD37C,.018*%
%ADD38C,.005*%
%ADD39C,.006*%
%ADD44C,.03004*%
%ADD43C,.05004*%
%ADD62C,.06204*%
%ADD41C,.03604*%
%ADD52C,.06504*%
%ADD49C,.07404*%
%ADD42C,.05604*%
%ADD51C,.04904*%
%ADD53C,.08704*%
%ADD40C,.12802*%
%ADD58C,.13236*%
%ADD57C,.16406*%
%ADD63C,.198*%
%ADD61C,.12717*%
%ADD54C,.13266*%
%ADD48R,.06502X.06502*%
%ADD56C,.28352*%
%ADD47R,.06504X.06502*%
%ADD46R,.06502X.06504*%
%ADD50R,.07404X.07404*%
%ADD45R,.06504X.06504*%
%ADD60O,.28352X.32289*%
%ADD55C,.39376*%
%ADD59C,.39377*%
G75*
%LPD*%
G75*
G36*
G01X123963Y1831628D02*
X135877D01*
G02X136737Y1830118I0J-1000D01*
G03X143103I3183J-1890D01*
G02X143963Y1831628I860J510D01*
G01X146774D01*
X148924Y1829478D01*
X159822D01*
G03X159956Y1829483I-4J1902D01*
G02X160454Y1828795I35J-499D01*
G03X162309Y1829653I1390J-570D01*
G02X161654Y1830872I309J951D01*
G03X159822Y1833282I-1832J509D01*
G01X150500D01*
X148350Y1835432D01*
X110040D01*
X90284Y1815675D01*
Y1753623D01*
X93866Y1750041D01*
X93865Y1609792D01*
G02X92158Y1609085I-1000J0D01*
G01X54908Y1646336D01*
Y1760076D01*
X49162Y1765822D01*
G02X49056Y1766372I354J353D01*
G03X46771Y1764087I-4000J1715D01*
G01X46912Y1764148D01*
X47213Y1764090D01*
X52304Y1758998D01*
Y1755134D01*
G02X50597Y1754427I-1000J0D01*
G01X35636Y1769388D01*
X27754D01*
X27500Y1769560D01*
X27443Y1769703D01*
G03X19980Y1770776I-4041J-1616D01*
G02X18194Y1771393I-786J618D01*
G01Y1810644D01*
X21137Y1813587D01*
G02X21687Y1813693I353J-354D01*
G03X26863Y1820331I1715J4000D01*
G02X27658Y1821938I795J607D01*
G01X38971D01*
X40704Y1820204D01*
Y1813342D01*
X49408D01*
Y1822044D01*
X42545D01*
X40049Y1824540D01*
X15867D01*
X9088Y1817761D01*
Y1764382D01*
X15780Y1757689D01*
Y1664178D01*
X44499Y1635459D01*
G02X43792Y1633752I-707J-707D01*
G01X37565D01*
X36389Y1632576D01*
X5351D01*
X2004Y1635923D01*
Y2064961D01*
G02X5905Y2068862I3901J0D01*
G01X92520D01*
G03X100429Y2076772I0J7909D01*
G01Y2080709D01*
G02X104331Y2084610I3902J-1D01*
G01X397638D01*
G02X403508Y2078740I0J-5870D01*
G01Y7874D01*
G02X397638Y2004I-5870J0D01*
G01X104331D01*
G02X100429Y5906I0J3902D01*
G01Y9843D01*
G03X92520Y17752I-7909J0D01*
G01X5906D01*
G02X2004Y21654I0J3902D01*
G01Y496146D01*
X6252Y500394D01*
X45040D01*
G02X45747Y498687I0J-1000D01*
G01X25148Y478087D01*
Y448792D01*
X31434Y442506D01*
Y428988D01*
X31294Y428753D01*
X31174Y428687D01*
G03X33733Y422739I1561J-2853D01*
G02X35040Y421787I307J-952D01*
G01Y421725D01*
X41238Y415528D01*
Y414429D01*
X43534Y412133D01*
G02X42827Y410425I-707J-708D01*
G01X34984D01*
X30983Y414427D01*
G02X30856Y414921I353J354D01*
G03X25671Y418347I-3121J913D01*
G02X24537Y418253I-635J773D01*
G01Y423127D01*
G03X20933I-1802J2707D01*
G01Y419086D01*
X14484D01*
Y412582D01*
X18439D01*
X26499Y404522D01*
X53943D01*
X61886Y412465D01*
Y430921D01*
X36651Y456156D01*
Y472649D01*
X86084Y522082D01*
Y556562D01*
X78924Y563722D01*
Y767160D01*
X45019Y801065D01*
Y812330D01*
X35766Y821583D01*
X35762Y821661D01*
G03X35255Y823052I-2499J-123D01*
G02X36051Y824658I796J606D01*
G01X37333D01*
X49122Y836446D01*
X78035D01*
X86038Y828444D01*
Y821327D01*
G02X84086Y821019I-1000J-1D01*
G03X45666Y814961I-18732J-6058D01*
G03X84086Y808902I19688J-1D01*
G02X86038Y808594I952J-307D01*
G01Y759366D01*
X93965Y751439D01*
X93985Y751265D01*
G03X95979Y753259I1790J204D01*
G01X95805Y753279D01*
X88640Y760444D01*
X88641Y761528D01*
G02X89494Y761881I500J0D01*
G01X104292Y747084D01*
X104297D01*
G02X105238Y745746I0J-1000D01*
G03X108632I1697J-607D01*
G02X109573Y747084I941J338D01*
G01X115641D01*
G02X116551Y745669I0J-1000D01*
G03X121509Y740790I3369J-1535D01*
G02X122938Y739887I429J-903D01*
G01Y738381D01*
G02X121509Y737478I-1000J0D01*
G03Y730790I-1589J-3344D01*
G02X122938Y729887I429J-903D01*
G01Y728381D01*
G02X121509Y727478I-1000J0D01*
G03Y720790I-1589J-3344D01*
G02X122938Y719887I429J-903D01*
G01Y718993D01*
X121684Y717739D01*
G02X121163Y717621I-354J353D01*
G03X116433Y712891I-1243J-3487D01*
G02X116315Y712370I-471J-167D01*
G01X88516Y684570D01*
Y438441D01*
X98084Y428873D01*
Y409463D01*
X108624Y398922D01*
X115585D01*
G02X116507Y397535I0J-1000D01*
G03X116447Y397383I3412J-1435D01*
G02X115608Y397219I-469J173D01*
G03X113146Y395552I-1110J-1012D01*
G01X113196Y395449D01*
Y371288D01*
X91342Y349434D01*
Y50050D01*
X99973Y41419D01*
X100011Y41311D01*
G03X101922Y43222I1419J492D01*
G01X101814Y43260D01*
X101618Y43456D01*
G02X101971Y44309I353J353D01*
G01X105240D01*
X109654Y39896D01*
Y36976D01*
G02X108077Y36159I-1000J0D01*
G03Y33215I-1040J-1472D01*
G02X109654Y32398I577J-817D01*
G01Y28516D01*
G02X108048Y27720I-1000J0D01*
G03X108618Y25585I-1090J-1435D01*
G02X110247Y25903I921J-389D01*
G01X116418Y19732D01*
X116482Y19450D01*
X116433Y19314D01*
G03X118677Y21558I3487J-1243D01*
G02X118156Y21676I-167J471D01*
G01X112256Y27575D01*
Y40974D01*
X106318Y46912D01*
X102538D01*
X95438Y54012D01*
Y66950D01*
G02X97146Y67657I1000J0D01*
G01X102893Y61909D01*
X102931Y61801D01*
G03X104842Y63712I1419J492D01*
G01X104734Y63750D01*
X97358Y71125D01*
Y73354D01*
G02X99066Y74061I1000J0D01*
G01X110086Y63040D01*
Y60752D01*
G02X109074Y59752I-1000J0D01*
G03Y56748I-20J-1502D01*
G02X110086Y55748I12J-1000D01*
G01Y52139D01*
G02X108486Y51339I-1000J0D01*
G03Y48457I-1081J-1441D01*
G02X110086Y47657I600J-800D01*
G01Y46493D01*
X114852Y41728D01*
X116040D01*
G02X116865Y40163I0J-1000D01*
G03X122975I3055J-2092D01*
G02X123800Y41728I825J565D01*
G01X134140D01*
X136246Y39622D01*
G02X136371Y39126I-354J-353D01*
G03X138865Y41620I3549J-1055D01*
G02X138369Y41745I-143J479D01*
G01X135384Y44730D01*
X123998D01*
G02X123131Y46228I0J1000D01*
G03X117192Y45568I-3211J1843D01*
G01X117323Y45425D01*
Y45230D01*
G02X116823Y44730I-500J0D01*
G01X116096D01*
X113090Y47737D01*
Y64284D01*
X107928Y69445D01*
G02X108087Y70988I707J707D01*
G03X108652Y71673I-824J1256D01*
G02X110284Y72000I925J-380D01*
G01X110355Y71930D01*
X116187D01*
G02X116981Y70322I0J-1000D01*
G03X122859I2939J-2251D01*
G02X123653Y71930I794J608D01*
G01X136187D01*
G02X136981Y70322I0J-1000D01*
G03X143520Y67210I2939J-2251D01*
G01X143553Y67347D01*
X143653Y67447D01*
G02X144360I354J-353D01*
G01X144688Y67120D01*
Y24679D01*
X141581Y21573D01*
X141299Y21509D01*
X141163Y21558D01*
G03X143407Y19314I-1243J-3487D01*
G02X143525Y19835I471J167D01*
G01X147290Y23601D01*
Y68198D01*
X141949Y73540D01*
G02X142074Y75060I707J707D01*
G03X136804Y76072I-2154J3011D01*
G02X135962Y74532I-842J-540D01*
G01X123878D01*
G02X123036Y76072I0J1000D01*
G03X116804I-3116J1999D01*
G02X115962Y74532I-842J-540D01*
G01X111433D01*
X102516Y83449D01*
Y329860D01*
X136017Y363360D01*
G02X137404Y363387I708J-707D01*
G03X143407Y367345I2516J2715D01*
G02X143525Y367866I471J167D01*
G01X146583Y370925D01*
G02X148290Y370218I707J-707D01*
G01Y367041D01*
X137847Y356598D01*
X130916D01*
X104178Y329860D01*
Y94120D01*
X105312Y92987D01*
Y85169D01*
G03X109114I1901J0D01*
G01Y92641D01*
G02X110822Y93348I1000J0D01*
G01X112932Y91238D01*
X115747D01*
G02X116634Y89777I0J-1000D01*
G03X123206I3286J-1706D01*
G02X124093Y91238I887J461D01*
G01X135747D01*
G02X136634Y89777I0J-1000D01*
G03X143206I3286J-1706D01*
G02X144093Y91238I887J461D01*
G01X156771D01*
X158072Y89936D01*
G03X159051Y89415I1344J1345D01*
G02X159850Y88304I-193J-981D01*
G03X159879Y87754I1489J-197D01*
G02X158905Y86519I-972J-235D01*
G03X160361Y85371I-4J-1502D01*
G02X161335Y86606I972J235D01*
G03X161855Y89518I3J1502D01*
G02X161240Y90741I344J939D01*
G03X160762Y92626I-1823J541D01*
G01X158347Y95040D01*
X114508D01*
X110846Y98703D01*
Y327097D01*
X114511Y330763D01*
G02X116218Y330056I707J-707D01*
G01Y324370D01*
X123622D01*
Y331773D01*
X117935D01*
G02X117228Y333480I0J1000D01*
G01X133679Y349930D01*
X140610D01*
X154958Y364278D01*
Y380426D01*
X169766Y395234D01*
Y441316D01*
X158029Y453052D01*
X116910D01*
X113402Y456560D01*
Y675503D01*
X114511Y676612D01*
G02X116218Y675905I707J-707D01*
G01Y672400D01*
X123622D01*
Y679804D01*
X120117D01*
G02X119410Y681511I0J1000D01*
G01X133794Y695894D01*
X147148D01*
X157704Y706450D01*
Y721197D01*
G02X159318Y721985I1000J-1D01*
G03X163878Y733804I4068J5220D01*
G02X163246Y735509I75J997D01*
G01X179190Y751453D01*
Y796256D01*
X151728Y823719D01*
Y833440D01*
X144314Y840854D01*
X118710D01*
X117146Y842418D01*
Y909780D01*
G02X118523Y910706I1000J0D01*
G03Y917562I1397J3428D01*
G02X117146Y918488I-377J926D01*
G01Y919780D01*
G02X118523Y920706I1000J0D01*
G03X123163Y925919I1397J3428D01*
G02X124039Y927402I876J483D01*
G01X135801D01*
G02X136677Y925919I0J-1000D01*
G03X143163I3243J-1785D01*
G02X144039Y927402I876J483D01*
G01X145098D01*
X154918Y937222D01*
X172929D01*
X174666Y935484D01*
G03X177356Y938174I1345J1345D01*
G01X175189Y940340D01*
G02Y941048I353J354D01*
G01X177334Y943192D01*
G03X174644Y945882I-1345J1345D01*
G01X173081Y944318D01*
X149667D01*
X146282Y940934D01*
X144075D01*
G02X143192Y942401I1J1000D01*
G03X143088Y946050I-3272J1733D01*
G02X143943Y947568I855J518D01*
G01X145492D01*
X153694Y955770D01*
X173066D01*
X174216Y954619D01*
G03X176906Y957309I1345J1345D01*
G01X174742Y959472D01*
G02Y960180I353J354D01*
G01X176704Y962141D01*
G03X174014Y964831I-1345J1345D01*
G01X172439Y963256D01*
X150839D01*
X148485Y960902D01*
X144058D01*
G02X143178Y962376I0J1000D01*
G03X136662I-3258J1758D01*
G02X135782Y960902I-880J-474D01*
G01X124058D01*
G02X123178Y962376I0J1000D01*
G03X116662I-3258J1758D01*
G02X115782Y960902I-880J-474D01*
G01X115243D01*
X107193Y952851D01*
G02X105486Y953558I-707J707D01*
G01Y968372D01*
X107296Y970183D01*
Y972040D01*
G03X104393Y973656I-1901J0D01*
G02X103813Y973693I-264J425D01*
G03X101266Y973565I-1203J-1473D01*
G01X100700Y972998D01*
G02X99847Y973352I-353J354D01*
G01X99846Y984456D01*
X101988Y986598D01*
Y998145D01*
G03Y1000637I-1301J1246D01*
G01Y1016252D01*
X147116Y1061380D01*
Y1076809D01*
X143422Y1080504D01*
X143358Y1080786D01*
X143407Y1080922D01*
G03X141163Y1078678I-3487J1243D01*
G02X141684Y1078560I167J-471D01*
G01X144514Y1075731D01*
Y1075197D01*
G02X142749Y1074552I-1000J0D01*
G03Y1069778I-2829J-2387D01*
G02X144514Y1069133I765J-645D01*
G01Y1065197D01*
G02X142749Y1064552I-1000J0D01*
G03X136433Y1060922I-2829J-2388D01*
G01X136482Y1060786D01*
X136418Y1060504D01*
X96838Y1020923D01*
Y992205D01*
G03X96349Y991163I1301J-1246D01*
G01X96329Y990989D01*
X95588Y990249D01*
Y933247D01*
G02X93881Y932540I-1000J0D01*
G01X89908Y936514D01*
Y1015929D01*
X129214Y1055236D01*
Y1092065D01*
X122488Y1098791D01*
G02Y1099499I354J354D01*
G01X122491Y1099501D01*
X122497Y1099507D01*
X122498Y1099508D01*
G03X123338Y1103587I-2578J2657D01*
G02X124261Y1104972I923J385D01*
G01X135273D01*
X136418Y1103826D01*
X136482Y1103544D01*
X136433Y1103408D01*
G03X138677Y1105652I3487J-1243D01*
G02X138156Y1105770I-167J471D01*
G01X136351Y1107574D01*
X122956D01*
G02X122310Y1109338I0J1000D01*
G03X116575Y1113752I-2390J2827D01*
G02X116124Y1113466I-452J214D01*
G01X115609D01*
X114084Y1114992D01*
G02X113954Y1115474I353J354D01*
G03X111001Y1115827I-1451J386D01*
G02X110002Y1114806I-999J-21D01*
G01X106213D01*
X99670Y1108262D01*
Y1065002D01*
X83108Y1048440D01*
G02X81400Y1049147I-708J707D01*
G01Y1057273D01*
G02X82530Y1058264I1000J-1D01*
G03Y1061838I233J1787D01*
G02X81400Y1062829I-130J992D01*
G01Y1084295D01*
X95278Y1098172D01*
Y1116351D01*
X106311Y1127384D01*
X109462D01*
X111745Y1129667D01*
X117189D01*
G03X123251Y1133779I2731J2498D01*
G02X124151Y1135216I900J437D01*
G01X135689D01*
G02X136589Y1133779I0J-1000D01*
G03X143251I3331J-1614D01*
G02X144151Y1135216I900J437D01*
G01X157628D01*
X158037Y1134806D01*
G03X160758Y1134838I1345J1345D01*
G02X162188Y1134855I723J-690D01*
G01X167396Y1129646D01*
Y1107556D01*
X148804Y1088964D01*
Y1034437D01*
X158743Y1024498D01*
X172706D01*
X174552Y1022652D01*
G03X177242Y1025342I1345J1345D01*
G01X174831Y1027752D01*
G02Y1028460I353J354D01*
G01X176793Y1030421D01*
G03X174103Y1033111I-1345J1345D01*
G01X172346Y1031354D01*
X161584D01*
X155660Y1037278D01*
Y1086123D01*
X174252Y1104715D01*
Y1132487D01*
X147806Y1158932D01*
X118433D01*
X115334Y1162032D01*
Y1259124D01*
G02X117096Y1259771I1000J0D01*
G03Y1264559I2824J2394D01*
G02X115334Y1265206I-762J647D01*
G01Y1269124D01*
G02X117096Y1269771I1000J0D01*
G03Y1274559I2824J2394D01*
G02X115334Y1275206I-762J647D01*
G01Y1279124D01*
G02X117096Y1279771I1000J0D01*
G03Y1284559I2824J2394D01*
G02X115334Y1285206I-762J647D01*
G01Y1289124D01*
G02X117096Y1289771I1000J0D01*
G03Y1294559I2824J2394D01*
G02X115334Y1295206I-762J647D01*
G01Y1299124D01*
G02X117096Y1299771I1000J0D01*
G03Y1304559I2824J2394D01*
G02X115334Y1305206I-762J647D01*
G01Y1309124D01*
G02X117096Y1309771I1000J0D01*
G03Y1314559I2824J2394D01*
G02X115334Y1315206I-762J647D01*
G01Y1319124D01*
G02X117096Y1319771I1000J0D01*
G03Y1324559I2824J2394D01*
G02X115334Y1325206I-762J647D01*
G01Y1329124D01*
G02X117096Y1329771I1000J0D01*
G03Y1334559I2824J2394D01*
G02X115334Y1335206I-762J647D01*
G01Y1339124D01*
G02X117096Y1339771I1000J0D01*
G03Y1344559I2824J2394D01*
G02X115334Y1345206I-762J647D01*
G01Y1349124D01*
G02X117096Y1349771I1000J0D01*
G03Y1354559I2824J2394D01*
G02X115334Y1355206I-762J647D01*
G01Y1359124D01*
G02X117096Y1359771I1000J0D01*
G03Y1364559I2824J2394D01*
G02X115334Y1365206I-762J647D01*
G01Y1367964D01*
G02X115834Y1368464I500J0D01*
G01X123622D01*
Y1375866D01*
X115834D01*
G02X115334Y1376366I0J500D01*
G01Y1379953D01*
X127296Y1391916D01*
X149982D01*
X156091Y1398025D01*
G02X157447Y1398078I707J-707D01*
G03X158472Y1401244I1171J1370D01*
G02X157392Y1402241I-80J997D01*
G01Y1421453D01*
G02X159047Y1422208I1000J0D01*
G03Y1432202I4338J4997D01*
G02X157392Y1432958I-655J755D01*
G01Y1448420D01*
G02X158677Y1449378I1000J0D01*
G03Y1452832I515J1727D01*
G02X157392Y1453790I-285J958D01*
G01Y1474762D01*
G02X158721Y1475706I1000J0D01*
G03X159543Y1478590I495J1418D01*
G02X159054Y1480273I218J976D01*
G01X160871Y1482089D01*
G03X158181Y1484779I-1345J1345D01*
G01X153588Y1480186D01*
Y1479035D01*
G02X151881Y1478328I-1000J0D01*
G01X143321Y1486888D01*
X118890D01*
X114863Y1490916D01*
G03X112905Y1491371I-1344J-1345D01*
G02X111582Y1492318I-323J947D01*
G01Y1718095D01*
X114511Y1721024D01*
G02X116218Y1720317I707J-707D01*
G01Y1716496D01*
X123622D01*
Y1723898D01*
X119800D01*
G02X119093Y1725606I0J1000D01*
G01X147956Y1754468D01*
Y1795971D01*
X144397Y1799530D01*
X143571D01*
X143327Y1799684D01*
X143265Y1799815D01*
G03X142793Y1795893I-3345J-1587D01*
G02X144276Y1795969I776J-631D01*
G01X145352Y1794893D01*
Y1755546D01*
X110774Y1720967D01*
G02X109067Y1721674I-707J707D01*
G01X109066Y1725534D01*
X138259Y1754726D01*
X138541Y1754790D01*
X138677Y1754741D01*
G03X138369Y1761589I1243J3487D01*
G02X136950Y1762497I-419J908D01*
G01Y1763959D01*
G02X138369Y1764867I1000J0D01*
G03Y1771589I1551J3361D01*
G02X136950Y1772497I-419J908D01*
G01Y1773417D01*
X138259Y1774726D01*
X138541Y1774790D01*
X138677Y1774741D01*
G03X136433Y1776985I1243J3487D01*
G01X136482Y1776849D01*
X136418Y1776567D01*
X134346Y1774495D01*
Y1761089D01*
X122929Y1749671D01*
G02X121222Y1750378I-707J707D01*
G01Y1754432D01*
G02X121507Y1754883I500J0D01*
G03X118333I-1587J3345D01*
G02X118618Y1754432I-215J-451D01*
G01Y1748523D01*
X113302Y1743206D01*
G02X111594Y1743913I-708J707D01*
G01Y1792097D01*
X108848Y1794844D01*
X108810Y1794952D01*
G03X108195Y1795729I-1419J-492D01*
G02X108023Y1797281I535J845D01*
G01X108664Y1797922D01*
X111455D01*
X118259Y1804726D01*
X118541Y1804790D01*
X118677Y1804741D01*
G03X116433Y1806985I1243J3487D01*
G01X116482Y1806849D01*
X116418Y1806567D01*
X110377Y1800526D01*
X109531D01*
G02X108563Y1801777I0J1000D01*
G03X105931Y1800662I-1744J453D01*
G02X106145Y1799085I-493J-870D01*
G01X102392Y1795331D01*
Y1744502D01*
X102138Y1744248D01*
G02X100431Y1744955I-707J707D01*
G01X100430Y1752762D01*
X96848Y1756344D01*
Y1809810D01*
X110164Y1823125D01*
G03X107474Y1825815I-1345J1345D01*
G01X94940Y1813280D01*
G02X94086Y1813634I-354J354D01*
G01Y1814099D01*
X111616Y1831628D01*
X115877D01*
G02X116737Y1830118I0J-1000D01*
G03X123103I3183J-1890D01*
G02X123963Y1831628I860J510D01*
G37*
G36*
G01X104331Y2004D02*
G02X100429Y5906I0J3902D01*
G01Y9843D01*
G03X92520Y17752I-7909J0D01*
G01X5906D01*
G02X2004Y21654I0J3902D01*
G01Y522301D01*
X3998D01*
Y21718D01*
G03X5905Y19745I1907J-64D01*
G01X5906D01*
Y19746D01*
X91602D01*
Y19745D01*
X92520D01*
G02X102422Y9843I-1J-9903D01*
G01Y5906D01*
G03X104330Y3997I1908J-1D01*
G01X104331D01*
Y3998D01*
X397638D01*
G03X401514Y7874I0J3876D01*
G01Y1910871D01*
G02X401520Y1910949I1000J-38D01*
G01X401514D01*
Y2078740D01*
G03X397638Y2082616I-3876J0D01*
G01X104331D01*
Y2082617D01*
X104330D01*
G03X102422Y2080709I0J-1908D01*
G01Y2076772D01*
G02X99522Y2069769I-9903J-1D01*
G02X92520Y2066868I-7003J7002D01*
G01X5971D01*
G03X4556Y2066310I-65J-1907D01*
G03X3998Y2064961I1350J-1348D01*
G01Y1608721D01*
X2004D01*
Y2064961D01*
G02X5905Y2068862I3901J0D01*
G01X92520D01*
G03X100429Y2076772I0J7909D01*
G01Y2080709D01*
G02X104331Y2084610I3902J-1D01*
G01X397638D01*
G02X403508Y2078740I0J-5870D01*
G01Y7874D01*
G02X397638Y2004I-5870J0D01*
G01X104331D01*
G37*
G36*
G01X48044Y839050D02*
X36401Y827406D01*
G02X36048Y827260I-353J354D01*
G01X35748D01*
G02X35270Y827760I22J500D01*
G01Y827911D01*
X35352Y828036D01*
G03X35764Y829338I-2089J1377D01*
G03X35740Y829766I-2501J74D01*
G01X35723Y829883D01*
X35798Y830106D01*
X58668Y852976D01*
X69619D01*
G03Y855580I1246J1302D01*
G01X57590D01*
X33957Y831947D01*
X33734Y831872D01*
X33617Y831889D01*
G03X32455Y831780I-354J-2477D01*
G03X31581Y831264I809J-2368D01*
G02X29924Y832018I-657J754D01*
G01Y834680D01*
G02X31581Y835434I1000J0D01*
G03X35723Y837744I1682J1852D01*
G03X30897Y838100I-2460J-458D01*
G01X30845Y837948D01*
X30585Y837763D01*
X30424D01*
G02X29924Y838263I0J500D01*
G01Y838529D01*
X29155Y839297D01*
X27924Y840529D01*
X27849Y840752D01*
X27866Y840869D01*
G03X25743Y838746I-2477J354D01*
G02X26167Y838605I71J-495D01*
G01X26858Y837914D01*
X27320Y837451D01*
Y836725D01*
G02X26055Y835761I-1000J0D01*
G03Y830937I-666J-2412D01*
G02X27320Y829973I265J-964D01*
G01Y828268D01*
X28768Y826820D01*
X30931Y824658D01*
X31797D01*
G02X32297Y824158I0J-500D01*
G01Y824021D01*
X32160Y823787D01*
X32041Y823721D01*
G03X31064Y820344I1222J-2183D01*
G02X30198Y818902I-897J-442D01*
G01X27791D01*
G02X27391Y819102I0J500D01*
G03Y816100I-2002J-1501D01*
G02X27791Y816300I400J-300D01*
G01X30198D01*
G02X31064Y814858I-31J-1000D01*
G03Y812470I2199J-1194D01*
G02X30198Y811028I-897J-442D01*
G01X27791D01*
G02X27391Y811228I0J500D01*
G03Y808226I-2002J-1501D01*
G02X27791Y808426I400J-300D01*
G01X30198D01*
G02X31064Y806984I-31J-1000D01*
G03Y804596I2199J-1194D01*
G02X30198Y803154I-897J-442D01*
G01X27791D01*
G02X27391Y803354I0J500D01*
G03Y800352I-2002J-1501D01*
G02X27791Y800552I400J-300D01*
G01X30199D01*
G02X31057Y799095I-32J-1000D01*
G03X30871Y797181I2206J-1180D01*
G03X33617Y795438I2392J734D01*
G01X33734Y795455D01*
X33957Y795380D01*
X67420Y761917D01*
Y558957D01*
X74580Y551797D01*
Y527520D01*
X63899Y516839D01*
X62844D01*
X62101Y517582D01*
Y524376D01*
X55195Y531282D01*
Y535250D01*
G02X56479Y536210I1000J1D01*
G03Y551192I2516J7491D01*
G02X55195Y552152I-284J959D01*
G01Y672683D01*
G02X56511Y673633I1000J1D01*
G03X56819Y673551I616J1693D01*
G03X57002Y673529I306J1776D01*
G02X57934Y672531I-68J-997D01*
G01Y672016D01*
X57825Y671879D01*
G03X59231Y668956I1411J-1121D01*
G03X60538Y672004I5J1802D01*
G01Y737296D01*
X44913Y752921D01*
Y755451D01*
X36674Y763690D01*
X28966D01*
X27245Y765411D01*
X13327D01*
X9885Y761969D01*
X5507D01*
X3523Y759985D01*
X2776D01*
Y761333D01*
X2140Y761969D01*
X2004D01*
Y1360647D01*
X4542Y1363185D01*
X9410D01*
X11383Y1361212D01*
X17172D01*
X21843Y1356541D01*
X22538D01*
X23007Y1356199D01*
X23060Y1356062D01*
G03X27773Y1356195I2333J906D01*
G01X27823Y1356350D01*
X28086Y1356541D01*
X35680D01*
G02X36132Y1356254I0J-499D01*
G01Y1355659D01*
G02X34655Y1355113I-952J305D01*
G03Y1350949I-1388J-2082D01*
G02X36132Y1350403I525J-851D01*
G01Y1339911D01*
G02X34655Y1339365I-952J305D01*
G03Y1335201I-1388J-2082D01*
G02X36132Y1334655I525J-851D01*
G01Y1332037D01*
G02X34655Y1331491I-952J305D01*
G03Y1327327I-1388J-2082D01*
G02X36132Y1326781I525J-851D01*
G01Y1324163D01*
G02X34655Y1323617I-952J305D01*
G03Y1319453I-1388J-2082D01*
G02X36132Y1318907I525J-851D01*
G01Y1316289D01*
G02X34655Y1315743I-952J305D01*
G03Y1311579I-1388J-2082D01*
G02X36132Y1311033I525J-851D01*
G01Y1308415D01*
G02X34655Y1307869I-952J305D01*
G03X31489Y1304026I-1389J-2081D01*
G03X31654Y1303874I1776J1762D01*
G01X31734Y1303806D01*
X31837Y1303596D01*
G02X31741Y1303024I-450J-219D01*
G01X31682Y1302964D01*
X31411D01*
X27361Y1298914D01*
X27080D01*
G02X26580Y1299414I0J500D01*
G01Y1299491D01*
X26696Y1299710D01*
X26799Y1299780D01*
G03X23987I-1406J2070D01*
G02X24206Y1299366I-281J-414D01*
G01Y1299206D01*
X23914Y1298914D01*
X23543D01*
X19187Y1294558D01*
G02X17822Y1295027I-458J889D01*
G03X13066Y1294269I-2271J-1051D01*
G03X14016Y1292000I2485J-293D01*
G03X16213Y1291563I1535J1976D01*
G02X17430Y1290908I266J-965D01*
G01Y1289170D01*
G02X16213Y1288515I-951J310D01*
G03X15338Y1288595I-662J-2413D01*
G03X14325Y1283921I213J-2493D01*
G02X14693Y1282610I-521J-853D01*
G01X14202Y1282118D01*
Y1280593D01*
G02X14010Y1280199I-500J0D01*
G03X13352Y1277034I1541J-1971D01*
G02X12486Y1275592I-897J-442D01*
G01X10079D01*
G02X9679Y1275792I0J500D01*
G03Y1272790I-2002J-1501D01*
G02X10079Y1272990I400J-300D01*
G01X12486D01*
G02X13352Y1271548I-31J-1000D01*
G03X17793Y1269243I2199J-1194D01*
G02X19363Y1269502I884J-468D01*
G01X22298Y1266568D01*
X24249Y1264616D01*
X27417D01*
X28502Y1263532D01*
X30122Y1261912D01*
X30719D01*
G02X31432Y1260244I-31J-1000D01*
G03X35102I1835J-1701D01*
G02X35815Y1261912I744J668D01*
G01X36595D01*
X39824Y1265140D01*
X41986Y1267302D01*
Y1278165D01*
X43667Y1279847D01*
X46178Y1282358D01*
Y1313080D01*
G02X47084Y1314044I1000J-32D01*
G03X46757Y1317631I-103J1799D01*
G01X46745Y1317629D01*
X46744D01*
X46711Y1317625D01*
X46678D01*
G02X46178Y1318125I0J500D01*
G01Y1318561D01*
G02X46678Y1319061I500J0D01*
G01X46711D01*
X46744Y1319057D01*
X46745D01*
X46757Y1319055D01*
G03Y1322631I223J1788D01*
G01X46745Y1322629D01*
X46744D01*
X46711Y1322625D01*
X46678D01*
G02X46178Y1323125I0J500D01*
G01Y1323561D01*
G02X46678Y1324061I500J0D01*
G01X46711D01*
X46744Y1324057D01*
X46745D01*
X46757Y1324055D01*
G03Y1327631I223J1788D01*
G01X46745Y1327629D01*
X46744D01*
X46711Y1327625D01*
X46678D01*
G02X46178Y1328125I0J500D01*
G01Y1328561D01*
G02X46678Y1329061I500J0D01*
G01X46711D01*
X46744Y1329057D01*
X46745D01*
X46757Y1329055D01*
G03Y1332631I223J1788D01*
G01X46745Y1332629D01*
X46744D01*
X46711Y1332625D01*
X46678D01*
G02X46178Y1333125I0J500D01*
G01Y1333561D01*
G02X46678Y1334061I500J0D01*
G01X46711D01*
X46744Y1334057D01*
X46745D01*
X46757Y1334055D01*
G03Y1337631I223J1788D01*
G01X46745Y1337629D01*
X46744D01*
X46711Y1337625D01*
X46678D01*
G02X46178Y1338125I0J500D01*
G01Y1338561D01*
G02X46678Y1339061I500J0D01*
G01X46711D01*
X46744Y1339057D01*
X46745D01*
X46757Y1339055D01*
G03Y1342631I223J1788D01*
G01X46745Y1342629D01*
X46744D01*
X46711Y1342625D01*
X46678D01*
G02X46178Y1343125I0J500D01*
G01Y1343561D01*
G02X46678Y1344061I500J0D01*
G01X46711D01*
X46744Y1344057D01*
X46745D01*
X46757Y1344055D01*
G03X48465Y1346865I224J1788D01*
G01X48370Y1347002D01*
X55285Y1353917D01*
Y1463872D01*
X82919Y1491507D01*
G02X84606Y1490811I687J-728D01*
G01Y1419239D01*
X83696Y1418329D01*
X77442Y1412076D01*
Y1269000D01*
X94532Y1251911D01*
G02X94678Y1251558I-354J-353D01*
G01Y1145104D01*
G02X94532Y1144751I-500J0D01*
G01X73912Y1124132D01*
Y1106889D01*
X58914Y1091890D01*
Y1019026D01*
G03X61435Y1017229I1901J0D01*
G03X61904Y1017467I-618J1798D01*
G01X61963Y1017508D01*
X62259Y1017607D01*
X62530Y1017526D01*
X62586Y1017492D01*
G03X62872Y1017349I990J1623D01*
G03X65478Y1019115I705J1766D01*
G01Y1089169D01*
X66054Y1089745D01*
G02X66908Y1089392I354J-353D01*
G01Y1001278D01*
X64642Y999012D01*
X61258Y995627D01*
Y885990D01*
G02X60521Y885771I-401J0D01*
G03Y878783I-5363J-3494D01*
G02X61258Y878564I336J-219D01*
G01Y874045D01*
X69055Y866248D01*
X69075Y866074D01*
G03X71862Y864777I1790J204D01*
G02X72638Y864360I276J-417D01*
G01Y863892D01*
X71915Y863169D01*
X70835Y862088D01*
X70661Y862068D01*
G03X72655Y860074I204J-1790D01*
G01X72675Y860248D01*
X74213Y861785D01*
X75242Y862814D01*
Y927535D01*
X83620Y935913D01*
G02X85306Y935186I686J-727D01*
G01Y933176D01*
X87661Y930821D01*
X91179Y927304D01*
X91199Y927130D01*
G03X91688Y926088I1790J204D01*
G01Y921690D01*
X84736Y914738D01*
Y873134D01*
X87438Y870432D01*
Y851786D01*
X87437Y833139D01*
G02X85751Y832412I-1000J0D01*
G01X79113Y839050D01*
X48044D01*
G37*
G36*
G01X28528Y1283203D02*
X26087Y1280762D01*
X25864Y1280688D01*
X25747Y1280705D01*
G03X23826Y1280178I-353J-2477D01*
G02X22200Y1280958I-626J780D01*
G01Y1285397D01*
X25139Y1288336D01*
X28379D01*
X29362Y1289319D01*
G02X30982Y1289020I707J-707D01*
G03X31358Y1288422I2285J1019D01*
G01X31484Y1288272D01*
X31468Y1287883D01*
X28528Y1284942D01*
Y1283203D01*
G37*
G36*
G01X29924Y1265791D02*
X28495Y1267220D01*
X25327D01*
X17409Y1275137D01*
G02X17384Y1276525I707J707D01*
G03X17052Y1280229I-1833J1703D01*
G02X16852Y1280629I300J400D01*
G01Y1281020D01*
X17889Y1282057D01*
G02X19596Y1281350I707J-707D01*
G01Y1277774D01*
X24351Y1273020D01*
X25833D01*
X28980Y1269873D01*
Y1268864D01*
X30733Y1267111D01*
X30807Y1266888D01*
X30790Y1266771D01*
G03X30775Y1266190I2477J-355D01*
G01X30786Y1266078D01*
X30710Y1265870D01*
X30631Y1265791D01*
G02X29924I-354J353D01*
G37*
G36*
G01X18384Y1672409D02*
Y1714945D01*
G02X20134Y1715606I1000J0D01*
G03X25117Y1714480I3268J2874D01*
G01X25258Y1714541D01*
X25559Y1714483D01*
X28030Y1712012D01*
Y1675342D01*
X25559Y1672871D01*
X25258Y1672813D01*
X25117Y1672874D01*
G03X20134Y1671748I-1715J-4000D01*
G02X18384Y1672409I-750J661D01*
G37*
G36*
G01X27508Y1716215D02*
G02X27402Y1716765I354J353D01*
G03X20134Y1721354I-4000J1715D01*
G02X18384Y1722015I-750J661D01*
G01Y1758767D01*
X11690Y1765460D01*
Y1816683D01*
X16945Y1821938D01*
X19146D01*
G02X19941Y1820331I0J-1000D01*
G03X19402Y1815978I3461J-2638D01*
G02X19296Y1815428I-460J-197D01*
G01X15590Y1811722D01*
Y1766739D01*
X32218Y1750111D01*
Y1658388D01*
G02X30511Y1657681I-1000J0D01*
G01X24704Y1663489D01*
Y1664522D01*
X24875Y1664776D01*
X25018Y1664833D01*
G03X27402Y1670589I-1616J4041D01*
G02X27508Y1671139I460J197D01*
G01X30632Y1674264D01*
Y1713090D01*
X27508Y1716215D01*
G37*
G36*
G01X65354Y795260D02*
G02I0J19700D01*
G37*
G36*
G01X46772Y1466961D02*
G02X45065Y1467668I-707J707D01*
G01Y1507484D01*
G02X46997Y1507845I1000J-1D01*
G03X85042Y1514961I18357J7115D01*
G03X65588Y1534647I-19688J0D01*
G02X64893Y1536354I12J1000D01*
G01X66510Y1537971D01*
Y1552032D01*
X76476Y1561999D01*
Y1605621D01*
G02X78184Y1606328I1000J0D01*
G01X86244Y1598267D01*
Y1506433D01*
X46772Y1466961D01*
G37*
G36*
G01X65354Y1495260D02*
G02I0J19700D01*
G37*
G36*
G01X118156Y1456592D02*
G02X118677Y1456710I354J-353D01*
G03X123520Y1459336I1243J3487D01*
G01X123553Y1459473D01*
X123653Y1459573D01*
G02X124360I354J-353D01*
G01X124714Y1459220D01*
Y1416831D01*
X121581Y1413699D01*
X121299Y1413635D01*
X121163Y1413684D01*
G03X116433Y1408954I-1243J-3487D01*
G01X116482Y1408818D01*
X116418Y1408536D01*
X105118Y1397236D01*
G02X103417Y1397833I-707J707D01*
G03X101428Y1395844I-1791J-198D01*
G02X102025Y1394143I-110J-994D01*
G01X95200Y1387317D01*
Y1328489D01*
X98909Y1324780D01*
X98929Y1324606D01*
G03X100923Y1326600I1790J204D01*
G01X100749Y1326620D01*
X97802Y1329567D01*
Y1336679D01*
G02X98656Y1337032I500J0D01*
G01X98909Y1336780D01*
X98929Y1336606D01*
G03X102110Y1335665I1790J204D01*
G01X102182Y1335752D01*
X102383Y1335847D01*
X102496D01*
G02X102996Y1335347I0J-500D01*
G01Y1334928D01*
X100689Y1332620D01*
X100515Y1332600D01*
G03X102509Y1330606I204J-1790D01*
G01X102529Y1330780D01*
X103334Y1331585D01*
G02X105042Y1330878I708J-707D01*
G01Y1324973D01*
X100689Y1320620D01*
X100515Y1320600D01*
G03X102509Y1318606I204J-1790D01*
G01X102529Y1318780D01*
X105008Y1321259D01*
G02X106716Y1320552I708J-707D01*
G01Y1314647D01*
X100689Y1308620D01*
X100515Y1308600D01*
G03X102509Y1306606I204J-1790D01*
G01X102529Y1306780D01*
X106982Y1311233D01*
G02X108690Y1310526I708J-707D01*
G01Y1153491D01*
X116898Y1145282D01*
X151760D01*
X156317Y1140726D01*
G02X155610Y1139018I-707J-708D01*
G01X108692D01*
X88830Y1119156D01*
Y1101421D01*
X74544Y1087136D01*
Y1014871D01*
G03X77655Y1013403I1902J0D01*
G02X78290I318J-386D01*
G03X79809Y1012995I1209J1468D01*
G02X80972Y1012008I163J-987D01*
G01Y945906D01*
X67413Y932347D01*
G02X65705Y933054I-708J707D01*
G01X65706Y992810D01*
X71616Y998721D01*
Y1086227D01*
X86740Y1101351D01*
Y1119362D01*
X104572Y1137193D01*
Y1259152D01*
X89138Y1274586D01*
Y1402016D01*
X104454Y1417332D01*
Y1418297D01*
G02X104954Y1418797I500J0D01*
G02X105381Y1418557I0J-500D01*
G03X105977Y1421027I1540J935D01*
G02X104454Y1421879I-523J852D01*
G01Y1431680D01*
G02X105992Y1432522I1000J0D01*
G03X105390Y1434921I970J1518D01*
G01X105323Y1434803D01*
X105090Y1434666D01*
X104954D01*
G02X104454Y1435166I0J500D01*
G01Y1436191D01*
X115865Y1447602D01*
G02X117284Y1447598I708J-707D01*
G03X117994Y1453358I2636J2599D01*
G02X116474Y1454212I-520J854D01*
G01Y1454910D01*
X118156Y1456592D01*
G37*
G36*
G01X66510Y1585547D02*
X66533Y1585620D01*
G03Y1590364I-7538J2372D01*
G01X66510Y1590437D01*
Y1611034D01*
G02X68217Y1611741I1000J0D01*
G01X73874Y1606085D01*
Y1563077D01*
X68217Y1557421D01*
G02X66510Y1558128I-707J707D01*
G01Y1585547D01*
G37*
G36*
G01X116124Y762832D02*
G02X116575Y762547I0J-500D01*
G03X123607Y763805I3345J1587D01*
G02X125310Y764423I996J-89D01*
G01X126324Y763409D01*
Y751038D01*
G02X124617Y750331I-1000J0D01*
G01X123555Y751394D01*
X123475D01*
G02X123052Y752160I0J500D01*
G03X116481Y752764I-3132J1974D01*
G02X115552Y751394I-929J-370D01*
G01X113328D01*
X109294Y755428D01*
X105845D01*
X105742Y755478D01*
G03X105579Y755545I-652J-1353D01*
G01X105471Y755583D01*
X91440Y769613D01*
X91441Y785425D01*
G02X93148Y786132I1000J0D01*
G01X103236Y776043D01*
Y773406D01*
X113810Y762832D01*
X116124D01*
G37*
G36*
G01X85788Y1404761D02*
Y1408163D01*
X93670Y1416046D01*
Y1450884D01*
G02X94897Y1451858I1000J0D01*
G03X96655Y1452829I339J1463D01*
G01X96693Y1452937D01*
X103764Y1460009D01*
Y1472960D01*
G02X105472Y1473667I1000J0D01*
G01X116162Y1462976D01*
X116390D01*
G02X116810Y1462205I0J-500D01*
G03X116433Y1458954I3110J-2008D01*
G01X116482Y1458818D01*
X116418Y1458536D01*
X113870Y1455988D01*
Y1449289D01*
X109888Y1445307D01*
G02X108318Y1445509I-707J707D01*
G03X105853Y1443044I-1555J-910D01*
G02X106055Y1441474I-505J-863D01*
G01X101850Y1437269D01*
Y1418410D01*
X87495Y1404054D01*
G02X85788Y1404761I-707J707D01*
G37*
G36*
G01X104150Y426754D02*
Y409492D01*
G02X102442Y408785I-1000J0D01*
G01X100686Y410541D01*
Y427803D01*
G02X102394Y428510I1000J0D01*
G01X104150Y426754D01*
G37*
G36*
G01X117147Y443166D02*
X110062Y450251D01*
Y452108D01*
G02X111769Y452815I1000J0D01*
G01X115334Y449250D01*
X156453D01*
X159215Y446488D01*
G02X158508Y444780I-707J-708D01*
G01X152987D01*
X151372Y443166D01*
X117147D01*
G37*
G36*
G01X143984Y734700D02*
X143814D01*
X143544Y734908D01*
X143501Y735073D01*
G03X138677Y737621I-3581J-939D01*
G02X138156Y737739I-167J471D01*
G01X136306Y739589D01*
Y740226D01*
G02X137862Y741057I1000J0D01*
G03Y747211I2058J3077D01*
G02X136306Y748042I-556J831D01*
G01Y750226D01*
G02X137862Y751057I1000J0D01*
G03Y757211I2058J3077D01*
G02X136306Y758042I-556J831D01*
G01Y760226D01*
G02X137862Y761057I1000J0D01*
G03Y767211I2058J3077D01*
G02X136306Y768042I-556J831D01*
G01Y770226D01*
G02X137862Y771057I1000J0D01*
G03Y777211I2058J3077D01*
G02X136306Y778042I-556J831D01*
G01Y780226D01*
G02X137862Y781057I1000J0D01*
G03X136240Y783732I2058J3077D01*
G02X134539Y782916I-994J-109D01*
G01X126019Y791436D01*
X115096D01*
X114624Y791908D01*
G02Y792615I353J353D01*
G01X114663Y792654D01*
X114711Y792684D01*
G03X115042Y795638I-1014J1609D01*
G01X102714Y807966D01*
Y809240D01*
G02X104421Y809947I1000J0D01*
G01X117028Y797340D01*
X146304D01*
X157708Y785935D01*
G03X159011Y785379I1344J1345D01*
G02X159984Y784284I-23J-1000D01*
G03X161718Y785624I1495J-143D01*
G02X160903Y786842I158J987D01*
G03X160398Y788625I-1850J439D01*
G01X147880Y801142D01*
X118604D01*
X105486Y814261D01*
Y815038D01*
G02X106339Y815392I500J0D01*
G01X114455Y807276D01*
X147705D01*
X164588Y790393D01*
Y756150D01*
X159894Y751456D01*
G02X158267Y751771I-707J707D01*
G03X155902Y749406I-1657J-708D01*
G02X156217Y747779I-392J-920D01*
G01X144484Y736047D01*
Y735200D01*
G02X143984Y734700I-500J0D01*
G37*
G36*
G01X116031Y811078D02*
X108402Y818707D01*
X108403Y820840D01*
G02X110110Y821547I1000J0D01*
G01X114141Y817516D01*
X142674D01*
X147404Y812786D01*
G02X146697Y811078I-707J-708D01*
G01X116031D01*
G37*
G36*
G01X115717Y821318D02*
X111316Y825719D01*
Y830453D01*
G02X113024Y831160I1000J0D01*
G01X116820Y827364D01*
X142105D01*
X143986Y825483D01*
Y821818D01*
G02X143486Y821318I-500J0D01*
G01X115717D01*
G37*
G36*
G01X142738Y837050D02*
X147924Y831864D01*
Y829337D01*
G02X146217Y828630I-1000J0D01*
G01X143681Y831166D01*
X118396D01*
X114390Y835173D01*
X114389Y837381D01*
G02X116097Y838088I1000J0D01*
G01X117134Y837050D01*
X142738D01*
G37*
G36*
G01X118474Y1149085D02*
X112492Y1155067D01*
Y1157080D01*
G02X114200Y1157787I1000J0D01*
G01X116857Y1155130D01*
X146230D01*
X150567Y1150793D01*
G02X149860Y1149085I-707J-708D01*
G01X118474D01*
G37*
G36*
G01X147542Y384855D02*
Y417791D01*
X142547Y422787D01*
G02X142546Y423493I354J354D01*
G03X143253Y427713I-2626J2609D01*
G02X144153Y429148I900J435D01*
G01X151589D01*
X155643Y433203D01*
G02X157332Y432685I707J-707D01*
G03X159091Y434444I1475J284D01*
G02X158573Y436133I189J982D01*
G01X159179Y436739D01*
G02X159886I354J-353D01*
G01X159969Y436656D01*
X160044Y436435D01*
X160028Y436319D01*
G03X161866Y434658I1489J-200D01*
G02X163098Y433686I232J-972D01*
G01Y397997D01*
X149250Y384148D01*
G02X147542Y384855I-708J707D01*
G37*
%LPC*%
G75*
G36*
G01X94431Y418629D02*
G02X92690Y419140I-1208J-893D01*
G03X93139Y420669I-355J935D01*
G02X94880Y420158I1208J893D01*
G03X94431Y418629I355J-935D01*
G37*
G36*
G01X85042Y114961D02*
G02X45666I-19688J0D01*
G02X85042I19688J0D01*
G37*
G36*
G01Y464961D02*
G02X45666I-19688J0D01*
G02X85042I19688J0D01*
G37*
G36*
G01Y1864961D02*
G02X45666I-19688J0D01*
G02X85042I19688J0D01*
G37*
G36*
G01Y1164961D02*
G02X45666I-19688J0D01*
G02X85042I19688J0D01*
G37*
G36*
G01X26122Y1345527D02*
G02X14107Y1342598I-5650J-2929D01*
G02X14821Y1345528I6365J1D01*
G03X14395Y1346875I-888J460D01*
G02X18000Y1349605I1156J2219D01*
G03X19182Y1348831I979J205D01*
G02X21762Y1348830I1288J-6233D01*
G03X22944Y1349605I203J979D01*
G02X26548Y1346875I2449J-511D01*
G03X26122Y1345527I462J-887D01*
G37*
G36*
G01X26118Y987262D02*
G02X14103Y984333I-5650J-2929D01*
G02X14817Y987263I6365J1D01*
G03X14391Y988610I-888J460D01*
G02X17996Y991340I1156J2219D01*
G03X19178Y990566I979J205D01*
G02X21758Y990565I1288J-6233D01*
G03X22940Y991340I203J979D01*
G02X26544Y988610I2449J-511D01*
G03X26118Y987262I462J-887D01*
G37*
G36*
G01X46484Y867750D02*
G02X50416Y867707I1983J1528D01*
G02X46484Y867750I-1983J-1528D01*
G37*
G54D44*
X323403Y1172804D03*
X292614Y1864565D03*
X159075Y1825087D03*
X158456Y1129045D03*
X108819Y1812118D03*
X59127Y1257647D03*
X58356Y1279812D03*
X58416Y1272383D03*
X108574Y1463389D03*
X158956Y780982D03*
G54D43*
X343726Y348655D03*
X343816Y325935D03*
Y342461D03*
Y335272D03*
X343734Y311980D03*
X343816Y318634D03*
X318040Y1033718D03*
X318170Y1027081D03*
X318184Y1014094D03*
X318119Y1007303D03*
X318315Y1001286D03*
X318235Y1020657D03*
X325139Y532799D03*
X316791Y532871D03*
Y516704D03*
Y524432D03*
X325139Y524360D03*
Y516632D03*
X332685Y348655D03*
X332775Y325935D03*
Y342461D03*
Y335272D03*
X332693Y311980D03*
X332775Y318634D03*
X307215Y1924283D03*
X314810D03*
X300349Y1924103D03*
X292754D03*
X307215Y1917328D03*
X314810D03*
Y1910412D03*
X307215D03*
X300349Y1910232D03*
X292754D03*
X300349Y1917148D03*
X292754D03*
X300886Y1487015D03*
Y1493970D03*
X292715D03*
Y1487015D03*
X309464Y1487018D03*
Y1493973D03*
X301066Y1459083D03*
Y1465999D03*
X292895D03*
Y1459083D03*
X300886Y1480099D03*
X301066Y1472954D03*
X292895D03*
X292715Y1480099D03*
X309823Y1459086D03*
Y1466002D03*
X309464Y1480102D03*
X309823Y1472957D03*
X294691Y1200693D03*
X303159D03*
X311936Y1200692D03*
X294691Y1192254D03*
Y1184526D03*
X311936Y1184525D03*
Y1192253D03*
X303159Y1192254D03*
Y1184526D03*
X306999Y1033718D03*
X307129Y1027081D03*
X307143Y1014094D03*
X307274Y1001286D03*
X307078Y1007303D03*
X307194Y1020657D03*
X315187Y697267D03*
X304146D03*
Y688828D03*
X315187D03*
X304146Y671763D03*
X315187D03*
Y681100D03*
X304146D03*
Y652457D03*
Y661258D03*
X315187D03*
Y652457D03*
X292569Y532762D03*
Y516595D03*
Y524323D03*
X307966Y532586D03*
X300537Y532476D03*
Y524037D03*
X307966Y524147D03*
Y516419D03*
X300537Y516309D03*
X270115Y2067489D03*
Y2041985D03*
Y2059050D03*
Y2051322D03*
Y2020965D03*
Y2031480D03*
X273342Y1659908D03*
Y1652180D03*
Y1668347D03*
Y1632338D03*
Y1642843D03*
Y1621823D03*
X285995Y1541235D03*
Y1534319D03*
X271534Y1541055D03*
Y1534139D03*
X278400Y1541235D03*
Y1534319D03*
X285995Y1548190D03*
X271534Y1548010D03*
X278400Y1548190D03*
X270622Y1318954D03*
Y1310515D03*
Y1302787D03*
Y1293450D03*
Y1272430D03*
Y1282945D03*
X278182Y1200622D03*
X286721Y1200479D03*
X278182Y1192183D03*
Y1184455D03*
X286721Y1192040D03*
Y1184312D03*
X269975Y1145240D03*
X279015Y1145097D03*
X288363Y1144955D03*
X269975Y1124220D03*
Y1134735D03*
X288363Y1134450D03*
X279015Y1134592D03*
X288363Y1123935D03*
X279015Y1124077D03*
X274399Y982114D03*
Y990553D03*
Y974386D03*
X274544Y959859D03*
Y967106D03*
Y949344D03*
X278944Y617449D03*
Y591945D03*
Y609010D03*
Y601282D03*
Y572639D03*
Y581440D03*
X274531Y417794D03*
Y396774D03*
Y407289D03*
X279754Y65449D03*
X271572D03*
X288102D03*
X279754Y45572D03*
X271572D03*
X279754Y54944D03*
X271572D03*
X288102Y45572D03*
Y54944D03*
X245582Y2067489D03*
X258337D03*
Y2041985D03*
Y2059050D03*
Y2051322D03*
X245582Y2059050D03*
Y2051322D03*
Y2041985D03*
X258337Y2031480D03*
Y2020965D03*
X245582D03*
Y2031480D03*
X250288Y1840090D03*
Y1833135D03*
X267037Y1840093D03*
Y1833138D03*
X258459Y1833135D03*
Y1840090D03*
X267037Y1826222D03*
X250288Y1826219D03*
X258459D03*
X267396Y1812122D03*
Y1805206D03*
Y1819077D03*
X250468Y1805203D03*
Y1812119D03*
Y1819074D03*
X258639Y1805203D03*
Y1812119D03*
Y1819074D03*
X265759Y1706950D03*
X254718D03*
Y1714678D03*
X265759D03*
X265498Y1722140D03*
X254457D03*
X254718Y1676593D03*
Y1687108D03*
X265759D03*
Y1676593D03*
X254718Y1697613D03*
X265759D03*
X261564Y1652180D03*
Y1659908D03*
Y1668347D03*
Y1632338D03*
Y1642843D03*
Y1621823D03*
X263939Y1541055D03*
Y1534139D03*
Y1548010D03*
X259581Y1318954D03*
Y1310515D03*
Y1302787D03*
Y1293450D03*
Y1282945D03*
Y1272430D03*
X251251Y1145384D03*
X261219D03*
X251251Y1134879D03*
Y1124364D03*
X261219Y1134879D03*
Y1124364D03*
X262621Y982114D03*
Y990553D03*
Y974386D03*
X262766Y959859D03*
Y967106D03*
Y949344D03*
X263174Y855159D03*
Y862887D03*
X251396D03*
Y855159D03*
Y871326D03*
X263174D03*
X255021Y762510D03*
Y770949D03*
Y754782D03*
X267166Y617449D03*
Y591945D03*
Y601282D03*
Y609010D03*
Y572639D03*
Y581440D03*
X248714Y418041D03*
X257572Y417650D03*
X248714Y397021D03*
Y407536D03*
X257572Y407145D03*
Y396630D03*
X266040Y417651D03*
Y396631D03*
Y407146D03*
X252818Y259749D03*
Y252021D03*
Y268188D03*
X264596Y252021D03*
Y259749D03*
Y268188D03*
X252818Y232179D03*
Y242684D03*
X264596Y232179D03*
Y242684D03*
X252818Y221664D03*
X264596D03*
X253083Y170131D03*
Y161692D03*
X264861Y170131D03*
Y161692D03*
X253083Y153964D03*
X264861D03*
X264104Y65449D03*
X256566D03*
X264104Y45572D03*
X256566D03*
X264104Y54944D03*
X256566D03*
X224573Y2067489D03*
X234541D03*
Y2041985D03*
X224573Y2051322D03*
Y2041985D03*
X234541Y2059050D03*
Y2051322D03*
X224573Y2059050D03*
X234541Y2020965D03*
X224573D03*
X234541Y2031480D03*
X224573D03*
X226606Y1339840D03*
X235429D03*
X242925D03*
X226606Y1316842D03*
X235429D03*
X242925D03*
X226606Y1324285D03*
X235429D03*
X226606Y1332321D03*
X235429D03*
X242925Y1324285D03*
Y1332321D03*
X226777Y1308924D03*
X235600D03*
X243096D03*
X226642Y1301975D03*
X235465D03*
X226642Y1294491D03*
X235465D03*
X242961Y1301975D03*
Y1294491D03*
X226642Y1287272D03*
X243980Y762510D03*
Y770949D03*
X234012Y762510D03*
Y770949D03*
X243980Y754782D03*
X234012D03*
X239746Y417898D03*
Y396878D03*
Y407393D03*
X222732Y170131D03*
Y161692D03*
X232700Y170131D03*
Y161692D03*
X243741Y170131D03*
Y161692D03*
X222732Y153964D03*
X232700D03*
X243741D03*
X219178Y1339840D03*
Y1316842D03*
Y1324285D03*
Y1332321D03*
X219349Y1308924D03*
X219214Y1301975D03*
Y1294491D03*
Y1287272D03*
X158492Y1703772D03*
Y1678268D03*
Y1687605D03*
Y1695333D03*
Y1657248D03*
Y1667763D03*
X155749Y1338090D03*
Y1354257D03*
Y1345818D03*
Y1328753D03*
Y1318248D03*
Y1307733D03*
X166424Y1019737D03*
Y1003570D03*
Y1011298D03*
X166699Y993944D03*
Y983439D03*
Y972924D03*
X157272Y641144D03*
Y649583D03*
Y613574D03*
Y633416D03*
Y624079D03*
Y604773D03*
X165975Y303868D03*
Y312307D03*
Y276298D03*
Y286803D03*
Y296140D03*
Y265783D03*
X15547Y770357D03*
Y778231D03*
X25389Y770357D03*
Y778231D03*
X7673Y774293D03*
Y782167D03*
X15547Y786105D03*
Y801853D03*
X25389Y786105D03*
X7673Y790041D03*
Y797915D03*
Y805790D03*
X15547Y809727D03*
Y817601D03*
X7673Y813664D03*
Y821538D03*
Y829412D03*
X15547Y833349D03*
Y841223D03*
Y849097D03*
X25389D03*
X7673Y837286D03*
Y845160D03*
X15547Y856971D03*
Y872719D03*
X25389Y856971D03*
Y864845D03*
X7673Y860908D03*
Y868782D03*
Y876656D03*
X15547Y880593D03*
Y888467D03*
Y896341D03*
X25389Y880593D03*
Y888467D03*
Y896341D03*
X7673Y892404D03*
Y900278D03*
X15547Y912089D03*
Y919963D03*
X25389Y904215D03*
Y919963D03*
X7673Y908152D03*
Y916026D03*
X15547Y927837D03*
Y935711D03*
Y951459D03*
X25389Y927837D03*
Y935711D03*
Y943585D03*
X7673Y931774D03*
Y939648D03*
Y947522D03*
X15547Y959333D03*
Y967207D03*
Y975081D03*
X25389Y959333D03*
Y967207D03*
Y975081D03*
X7673Y955396D03*
Y971144D03*
Y979018D03*
Y994766D03*
X25389Y998703D03*
X7673Y1002640D03*
Y1010514D03*
X15547Y1006577D03*
Y1014451D03*
Y1022325D03*
X25389Y1014451D03*
Y1022325D03*
X7673Y1026262D03*
X15551Y1065629D03*
X25393D03*
X7677Y1061692D03*
X15551Y1073503D03*
Y1081377D03*
X25393D03*
Y1089251D03*
X7677Y1077440D03*
Y1085314D03*
Y1093188D03*
X15551Y1097125D03*
Y1104999D03*
Y1112873D03*
Y1120748D03*
X25393Y1097125D03*
Y1104999D03*
Y1120748D03*
X7677Y1101062D03*
Y1116810D03*
X15551Y1136496D03*
Y1144370D03*
X25393Y1128622D03*
Y1136496D03*
Y1144370D03*
X7677Y1124684D03*
Y1132558D03*
Y1140432D03*
X15551Y1152244D03*
Y1160118D03*
X25393D03*
Y1167992D03*
X7677Y1156180D03*
Y1164055D03*
X15551Y1175866D03*
Y1183740D03*
Y1191614D03*
X25393Y1175866D03*
Y1183740D03*
X7677Y1171929D03*
Y1179803D03*
X15551Y1199488D03*
Y1215236D03*
X25393Y1199488D03*
Y1207362D03*
Y1215236D03*
X7677Y1195551D03*
Y1203425D03*
Y1211299D03*
X15551Y1223110D03*
Y1230984D03*
Y1238858D03*
X25393Y1223110D03*
Y1238858D03*
X7677Y1219173D03*
Y1234921D03*
X15551Y1254606D03*
Y1262480D03*
X25393Y1246732D03*
Y1254606D03*
X7677Y1242795D03*
Y1250669D03*
Y1258543D03*
X15551Y1301850D03*
Y1309724D03*
X25393D03*
X7677Y1290039D03*
Y1297913D03*
Y1305787D03*
X15551Y1317598D03*
Y1325472D03*
Y1333346D03*
X25393Y1325472D03*
Y1333346D03*
X7677Y1321535D03*
Y1329409D03*
Y1337283D03*
Y1353031D03*
X33263Y774293D03*
Y782167D03*
Y790041D03*
Y845160D03*
Y860908D03*
Y868782D03*
Y876656D03*
Y884530D03*
Y900278D03*
Y908152D03*
Y916026D03*
Y923900D03*
Y939648D03*
Y947522D03*
Y955396D03*
Y963270D03*
Y979018D03*
Y994766D03*
Y1002640D03*
Y1010514D03*
Y1026262D03*
X33267Y1061692D03*
Y1069566D03*
Y1077440D03*
Y1085314D03*
Y1101062D03*
Y1108936D03*
Y1116810D03*
Y1124684D03*
Y1140432D03*
Y1148306D03*
Y1156180D03*
Y1164055D03*
Y1179803D03*
Y1187677D03*
Y1195551D03*
Y1203425D03*
Y1219173D03*
Y1227047D03*
Y1234921D03*
Y1242795D03*
G54D62*
X61298Y559882D03*
G54D41*
X391278Y765894D03*
X369748Y1921795D03*
X379403Y1917261D03*
X374775Y1919243D03*
X367829Y1566108D03*
X371523Y1204725D03*
X373674Y1199967D03*
X376472Y1194999D03*
X386816Y1179841D03*
X383276Y1184136D03*
X379335Y1189778D03*
X380186Y761742D03*
X386790Y774338D03*
X382892Y767710D03*
X376654Y754748D03*
X368907Y404308D03*
X374542Y401282D03*
X380878Y403999D03*
X380619Y410112D03*
X374442Y406857D03*
X379257Y52158D03*
X365720Y52336D03*
X372204Y56126D03*
X347676Y1922165D03*
X340336Y1922409D03*
X363411Y1923459D03*
X358318Y1920680D03*
X363361Y1918313D03*
X344402Y1911123D03*
X345537Y1916558D03*
X355364Y1570990D03*
X348245Y1575241D03*
X343402Y1572080D03*
X361011Y1568890D03*
X348710Y1570187D03*
X350690Y1403243D03*
X344130Y1401670D03*
X349855Y1104302D03*
X344099Y1106798D03*
X345578Y1047844D03*
X343656Y933725D03*
X344109Y751809D03*
X362577Y752783D03*
X342900Y580126D03*
X363825Y401768D03*
X342097Y401684D03*
X340373Y51579D03*
X345089Y56190D03*
X348289Y50863D03*
X359931Y52189D03*
X332399Y1926787D03*
X338309Y1927623D03*
X335730Y1753270D03*
X321283Y1753466D03*
X329887Y1752081D03*
X335963Y1573797D03*
X333474Y1566686D03*
X317243Y1574832D03*
X329399Y1571939D03*
X323720Y1570924D03*
X334646Y1400804D03*
X325636Y1399114D03*
X319404Y1401346D03*
X327932Y1289221D03*
X329619Y1284016D03*
X333242Y1276809D03*
X338047Y1282599D03*
X321978Y1282086D03*
X327452Y1279447D03*
X326558Y1126368D03*
X328989Y1121090D03*
X337509Y1109598D03*
X331920Y1116088D03*
X317592Y1053050D03*
X335677Y1048904D03*
X324246Y1051786D03*
X321425Y951577D03*
X328583Y933262D03*
X336160Y937262D03*
X333300Y928464D03*
X326646Y939788D03*
X323868Y929978D03*
X318557Y941178D03*
X324098Y946104D03*
X332527Y943746D03*
X329938Y948756D03*
X339615Y926357D03*
X327524Y758020D03*
X334010Y758588D03*
X329336Y762693D03*
X339012Y752859D03*
X331568Y752967D03*
X321742Y599041D03*
X319852Y593330D03*
X323751Y589155D03*
X333750Y595326D03*
X331867Y589810D03*
X320380Y576491D03*
X337387Y586230D03*
X317724Y588250D03*
X329636Y584715D03*
X319305Y582111D03*
X336617Y577978D03*
X320980Y423225D03*
X328950Y409216D03*
X326196Y413982D03*
X323313Y418313D03*
X335522Y404033D03*
X324709Y231580D03*
X320961Y250105D03*
X331046Y232021D03*
X329930Y245684D03*
X321899Y238137D03*
X318088Y231820D03*
X320372Y225979D03*
X338227Y61559D03*
X333889Y56021D03*
X331403Y51409D03*
X311539Y1753499D03*
X312077Y1575871D03*
X301734Y1513883D03*
X302267Y1524401D03*
X314183Y1403423D03*
X312698Y1172804D03*
X312527Y1162266D03*
X309678Y1053262D03*
X305867Y258589D03*
X314940Y252083D03*
X314914Y238162D03*
X306267Y241010D03*
X308057Y248863D03*
X279976Y1864565D03*
X280240Y1858668D03*
X255687Y812192D03*
X255837Y823626D03*
X265737Y473680D03*
X265722Y463102D03*
X257125Y115559D03*
X256947Y128276D03*
X173394Y1736051D03*
X176083Y1402321D03*
X175473Y1016296D03*
X175698Y1008730D03*
X175449Y997660D03*
X175742Y989958D03*
X175022Y980281D03*
X175135Y972490D03*
X156452Y1800821D03*
X163257Y1737619D03*
X165782Y1732903D03*
X156183Y1735240D03*
X168151Y1739208D03*
X150309Y1737009D03*
X170351Y1401324D03*
X164037Y1400226D03*
X156854Y1101031D03*
X157558Y51426D03*
X144878Y1738861D03*
X105152Y1118381D03*
X107173Y735219D03*
X107025Y725368D03*
X106709Y391219D03*
X106836Y376461D03*
X96684Y1081791D03*
X379572Y58441D03*
X387524Y76847D03*
X49441Y1238962D03*
X61866Y1309190D03*
X67568Y1307829D03*
X54543Y1308995D03*
X61866Y1342104D03*
X96510Y1395382D03*
X100719Y1312810D03*
X107006Y1452651D03*
X156865Y401207D03*
G54D52*
X52735Y2061661D03*
Y1957291D03*
Y216976D03*
X47735Y2051661D03*
X32735Y2061661D03*
X42735D03*
X47735Y1947291D03*
X32735Y1957291D03*
X42735D03*
Y243811D03*
X47735Y233811D03*
X37735D03*
X47735Y206976D03*
X42735Y216976D03*
Y34953D03*
X47735Y24953D03*
X27735Y2051661D03*
X22735Y2061661D03*
X27735Y1947291D03*
X22735Y1957291D03*
Y243811D03*
X27735Y233811D03*
X17735D03*
X27735Y206976D03*
X22735Y216976D03*
Y34953D03*
X27735Y24953D03*
X17735D03*
G54D49*
X139920Y2068228D03*
Y2048228D03*
Y2058228D03*
Y2018228D03*
Y2028228D03*
Y2038228D03*
Y1998228D03*
Y2008228D03*
Y1968228D03*
Y1978228D03*
Y1988228D03*
Y1958228D03*
Y1808228D03*
Y1818228D03*
Y1788228D03*
Y1710197D03*
Y1720197D03*
Y1680197D03*
Y1690197D03*
Y1700197D03*
Y1660197D03*
Y1670197D03*
Y1630197D03*
Y1640197D03*
Y1650197D03*
Y1610197D03*
Y1620197D03*
Y1372165D03*
Y1342165D03*
Y1352165D03*
Y1362165D03*
Y1322165D03*
Y1332165D03*
Y1292165D03*
Y1302165D03*
Y1312165D03*
Y1272165D03*
Y1282165D03*
Y1262165D03*
Y1112165D03*
Y1122165D03*
Y1092165D03*
Y1004134D03*
Y1014134D03*
Y1024134D03*
Y984134D03*
Y994134D03*
Y974134D03*
Y914134D03*
Y666102D03*
Y676102D03*
Y646102D03*
Y656102D03*
Y616102D03*
Y626102D03*
Y636102D03*
Y596102D03*
Y606102D03*
Y576102D03*
Y586102D03*
Y566102D03*
Y328071D03*
Y308071D03*
Y318071D03*
Y278071D03*
Y288071D03*
Y298071D03*
Y258071D03*
Y268071D03*
Y238071D03*
Y248071D03*
Y218071D03*
Y228071D03*
Y48071D03*
Y58071D03*
Y28071D03*
X119920Y2058228D03*
Y2048228D03*
Y2038228D03*
Y2028228D03*
Y2018228D03*
Y2008228D03*
Y1998228D03*
Y1988228D03*
Y1978228D03*
Y1968228D03*
Y1958228D03*
Y1818228D03*
Y1798228D03*
Y1788228D03*
Y1778228D03*
Y1768228D03*
Y1710197D03*
Y1700197D03*
Y1690197D03*
Y1680197D03*
Y1670197D03*
Y1660197D03*
Y1650197D03*
Y1640197D03*
Y1630197D03*
Y1620197D03*
Y1610197D03*
Y1122165D03*
Y1014134D03*
Y1004134D03*
Y994134D03*
Y984134D03*
Y974134D03*
Y666102D03*
Y656102D03*
Y646102D03*
Y636102D03*
Y626102D03*
Y616102D03*
Y606102D03*
Y596102D03*
Y586102D03*
Y576102D03*
Y566102D03*
Y318071D03*
Y308071D03*
Y298071D03*
Y288071D03*
Y278071D03*
Y268071D03*
Y258071D03*
Y248071D03*
Y238071D03*
Y228071D03*
Y218071D03*
Y58071D03*
Y28071D03*
Y1420197D03*
Y1430197D03*
Y1440197D03*
G54D42*
X362165Y1954705D03*
Y1944705D03*
X357165Y1959705D03*
Y1949705D03*
X352165Y1954705D03*
Y1944705D03*
X347165Y1959705D03*
Y1949705D03*
X342165Y1954705D03*
Y1944705D03*
X362165Y1779705D03*
X357165Y1784705D03*
Y1774705D03*
X352165Y1779705D03*
X347165Y1784705D03*
Y1774705D03*
X342165Y1779705D03*
X362165Y1769705D03*
X352165D03*
X342165D03*
Y1604705D03*
X347165Y1609705D03*
X352165Y1604705D03*
X357165Y1609705D03*
X362165Y1604705D03*
X342165Y1594705D03*
X347165Y1599705D03*
X352165Y1594705D03*
X357165Y1599705D03*
X362165Y1594705D03*
Y1429705D03*
Y1419705D03*
X357165Y1434705D03*
Y1424705D03*
X352165Y1429705D03*
Y1419705D03*
X347165Y1434705D03*
Y1424705D03*
X342165Y1429705D03*
Y1419705D03*
X362165Y1254705D03*
Y1244705D03*
X357165Y1259705D03*
Y1249705D03*
X352165Y1254705D03*
Y1244705D03*
X347165Y1259705D03*
Y1249705D03*
X342165Y1254705D03*
Y1244705D03*
X362165Y1079705D03*
X357165Y1084705D03*
Y1074705D03*
X352165Y1079705D03*
X347165Y1084705D03*
Y1074705D03*
X342165Y1079705D03*
X362165Y1069705D03*
X352165D03*
X342165D03*
X362165Y904705D03*
X357165Y909705D03*
X352165Y904705D03*
X347165Y909705D03*
X342165Y904705D03*
X362165Y894705D03*
X357165Y899705D03*
X352165Y894705D03*
X347165Y899705D03*
X342165Y894705D03*
X357166Y734705D03*
X347166D03*
X362166Y729705D03*
Y719705D03*
X357166Y724705D03*
X352166Y729705D03*
Y719705D03*
X347166Y724705D03*
X342166Y729705D03*
Y719705D03*
X362166Y554705D03*
Y544705D03*
X357166Y559705D03*
Y549705D03*
X352166Y554705D03*
Y544705D03*
X347166Y559705D03*
Y549705D03*
X342166Y554705D03*
Y544705D03*
X362165Y379705D03*
X357165Y384705D03*
Y374705D03*
X352165Y379705D03*
X347165Y384705D03*
Y374705D03*
X342165Y379705D03*
X362165Y369705D03*
X352165D03*
X342165D03*
X362165Y204705D03*
X357165Y209705D03*
X352165Y204705D03*
X347165Y209705D03*
X342165Y204705D03*
X362165Y194705D03*
X357165Y199705D03*
X352165Y194705D03*
X347165Y199705D03*
X342165Y194705D03*
X357165Y34705D03*
X347165D03*
X362165Y29705D03*
Y19705D03*
X357165Y24705D03*
X352165Y29705D03*
Y19705D03*
X347165Y24705D03*
X342165Y29705D03*
Y19705D03*
X323385Y1946890D03*
Y1957520D03*
X337165Y1959705D03*
Y1949705D03*
X323385Y1782520D03*
X337165Y1784705D03*
Y1774705D03*
X323385Y1771890D03*
X337165Y1609705D03*
X323385Y1607520D03*
X337165Y1599705D03*
X323385Y1596890D03*
Y1421890D03*
Y1432520D03*
X337165Y1434705D03*
Y1424705D03*
X323385Y1246890D03*
Y1257520D03*
X337165Y1259705D03*
Y1249705D03*
X323385Y1082520D03*
X337165Y1084705D03*
Y1074705D03*
X323385Y1071890D03*
Y907520D03*
X337165Y909705D03*
X323385Y896890D03*
X337165Y899705D03*
X337166Y734705D03*
X323386Y721890D03*
Y732520D03*
X337166Y724705D03*
X323386Y546890D03*
Y557520D03*
X337166Y559705D03*
Y549705D03*
X323385Y382520D03*
X337165Y384705D03*
Y374705D03*
X323385Y371890D03*
Y207520D03*
X337165Y209705D03*
X323385Y196890D03*
X337165Y199705D03*
Y34705D03*
X323385Y21890D03*
Y32520D03*
X337165Y24705D03*
X313385Y1946890D03*
Y1957520D03*
X303385D03*
Y1946890D03*
X293385Y1957520D03*
Y1946890D03*
X313385Y1782520D03*
X303385D03*
X293385D03*
X313385Y1771890D03*
X303385D03*
X293385D03*
Y1607520D03*
X303385D03*
X313385D03*
X293385Y1596890D03*
X303385D03*
X313385D03*
Y1421890D03*
Y1432520D03*
X303385D03*
Y1421890D03*
X293385Y1432520D03*
Y1421890D03*
X313385Y1246890D03*
Y1257520D03*
X303385D03*
Y1246890D03*
X293385Y1257520D03*
Y1246890D03*
X313385Y1082520D03*
X303385D03*
X293385D03*
X313385Y1071890D03*
X303385D03*
X293385D03*
X313385Y907520D03*
X303385D03*
X293385D03*
X313385Y896890D03*
X303385D03*
X293385D03*
X313386Y721890D03*
Y732520D03*
X303386D03*
Y721890D03*
X293386Y732520D03*
Y721890D03*
X313386Y546890D03*
Y557520D03*
X303386D03*
Y546890D03*
X293386Y557520D03*
Y546890D03*
X313385Y382520D03*
X303385D03*
X293385D03*
X313385Y371890D03*
X303385D03*
X293385D03*
X313385Y207520D03*
X303385D03*
X293385D03*
X313385Y196890D03*
X303385D03*
X293385D03*
X313385Y21890D03*
Y32520D03*
X303385D03*
Y21890D03*
X293385Y32520D03*
Y21890D03*
X283385Y1957520D03*
Y1946890D03*
X273385Y1957520D03*
Y1946890D03*
X283385Y1782520D03*
X273385D03*
X283385Y1771890D03*
X273385D03*
Y1607520D03*
X283385D03*
X273385Y1596890D03*
X283385D03*
Y1432520D03*
Y1421890D03*
X273385Y1432520D03*
Y1421890D03*
X283385Y1257520D03*
Y1246890D03*
X273385Y1257520D03*
Y1246890D03*
X283385Y1082520D03*
X273385D03*
X283385Y1071890D03*
X273385D03*
X283385Y907520D03*
X273385D03*
X283385Y896890D03*
X273385D03*
X283386Y732520D03*
Y721890D03*
X273386Y732520D03*
Y721890D03*
X283386Y557520D03*
Y546890D03*
X273386Y557520D03*
Y546890D03*
X283385Y382520D03*
X273385D03*
X283385Y371890D03*
X273385D03*
X283385Y207520D03*
X273385D03*
X283385Y196890D03*
X273385D03*
X283385Y32520D03*
Y21890D03*
X273385Y32520D03*
Y21890D03*
X263385Y1957520D03*
Y1946890D03*
X253385Y1957520D03*
Y1946890D03*
X263385Y1782520D03*
X253385D03*
X263385Y1771890D03*
X253385D03*
Y1607520D03*
X263385D03*
X253385Y1596890D03*
X263385D03*
Y1432520D03*
Y1421890D03*
X253385Y1432520D03*
Y1421890D03*
X263385Y1257520D03*
Y1246890D03*
X253385Y1257520D03*
Y1246890D03*
X263385Y1082520D03*
X253385D03*
X263385Y1071890D03*
X253385D03*
X263385Y907520D03*
X253385D03*
X263385Y896890D03*
X253385D03*
X263386Y732520D03*
Y721890D03*
X253386Y732520D03*
Y721890D03*
X263386Y557520D03*
Y546890D03*
X253386Y557520D03*
Y546890D03*
X263385Y382520D03*
X253385D03*
X263385Y371890D03*
X253385D03*
X263385Y207520D03*
X253385D03*
X263385Y196890D03*
X253385D03*
X263385Y32520D03*
Y21890D03*
X253385Y32520D03*
Y21890D03*
G54D51*
X79878Y2061343D03*
G54D53*
X45056Y1801158D03*
Y1784622D03*
G54D40*
X344826Y2035270D03*
X389572Y66182D03*
G54D58*
X163385Y27205D03*
Y202205D03*
Y377205D03*
X163386Y552205D03*
X163385Y902205D03*
Y1077205D03*
Y1252205D03*
Y1602205D03*
Y1777205D03*
Y1952205D03*
G54D57*
X57735Y2026661D03*
Y1922291D03*
Y390834D03*
Y268811D03*
Y181976D03*
Y59953D03*
X12735Y2026661D03*
Y1922291D03*
Y390834D03*
Y268811D03*
Y181976D03*
Y59953D03*
G54D63*
X65354Y814960D03*
Y1514960D03*
G54D61*
X20472Y1054606D03*
G54D54*
X373385Y1957520D03*
Y1782520D03*
Y1607520D03*
Y1432520D03*
Y1257520D03*
Y1082520D03*
Y907520D03*
X373386Y732520D03*
Y557520D03*
X373385Y382520D03*
Y207520D03*
Y32520D03*
G54D48*
X205387Y1731351D03*
X205923Y1648177D03*
X204859Y1557277D03*
X204333Y506517D03*
X52735Y243811D03*
Y34953D03*
X17735Y2051661D03*
Y1947291D03*
G54D56*
X307086Y308268D03*
G54D47*
X205310Y1823227D03*
X205122Y1206233D03*
X204596Y681645D03*
X203542Y73105D03*
G54D46*
X205905Y1998730D03*
X204069Y1900420D03*
X203243Y1474162D03*
X210091Y947202D03*
X203541Y421732D03*
X204597Y331786D03*
X204137Y247568D03*
X204069Y152050D03*
X17735Y206976D03*
G54D50*
X119920Y2068228D03*
Y1024134D03*
G54D45*
X205310Y2043388D03*
X204332Y1380966D03*
X205626Y1299104D03*
X205030Y1122856D03*
X209296Y1032544D03*
X205386Y856244D03*
X205626Y774526D03*
X206668Y598130D03*
G54D60*
X307086Y1883071D03*
G54D55*
X359842Y2003780D03*
Y1828780D03*
Y1653780D03*
Y1478780D03*
Y1303780D03*
Y1128780D03*
Y953780D03*
Y778780D03*
Y603780D03*
Y428780D03*
Y253780D03*
Y78780D03*
X307087Y2043504D03*
Y1693504D03*
Y1343504D03*
G54D59*
Y127165D03*
Y477165D03*
Y827165D03*
%LPD*%
G75*
G36*
G01X65354Y95260D02*
G02I0J19700D01*
G37*
G36*
G01Y445260D02*
G02I0J19700D01*
G37*
G36*
G01Y1145260D02*
G02I0J19700D01*
G37*
G36*
G01Y1845260D02*
G02I0J19700D01*
G37*
G36*
G01X326786Y127165D02*
G02I-19700J0D01*
G37*
G36*
G01Y477165D02*
G02I-19700J0D01*
G37*
G36*
G01Y827165D02*
G02I-19700J0D01*
G37*
G36*
G01Y1343504D02*
G02I-19700J0D01*
G37*
G36*
G01Y1693504D02*
G02I-19700J0D01*
G37*
G36*
G01X326787Y2043503D02*
G02I-19700J0D01*
G37*
%LPC*%
G75*
G54D63*
X65354Y114960D03*
Y464960D03*
Y1164960D03*
Y1864960D03*
X307086Y127165D03*
Y477165D03*
Y827165D03*
Y1343504D03*
Y1693504D03*
X307087Y2043503D03*
%LPD*%
G75*
G36*
G01X2004Y534064D02*
Y1597998D01*
X3998D01*
Y534064D01*
X2004D01*
G37*
G54D10*
X17735Y24953D03*
X27735D03*
X22735Y34953D03*
Y216976D03*
X27735Y206976D03*
X17735Y233811D03*
X27735D03*
X22735Y243811D03*
X27735Y415834D03*
X22735Y425834D03*
Y1957291D03*
X27735Y1947291D03*
X22735Y2061661D03*
X27735Y2051661D03*
X37735Y24953D03*
X47735D03*
X32735Y34953D03*
X42735D03*
Y216976D03*
X32735D03*
X47735Y206976D03*
X37735D03*
Y233811D03*
X47735D03*
X32735Y243811D03*
X42735D03*
X47735Y415834D03*
X37735D03*
X42735Y425834D03*
X32735D03*
X42735Y1957291D03*
X32735D03*
X47735Y1947291D03*
X37735D03*
X42735Y2061661D03*
X32735D03*
X47735Y2051661D03*
X37735D03*
X52735Y216976D03*
Y425834D03*
Y1957291D03*
Y2061661D03*
X189762Y73105D03*
X190289Y152050D03*
X190357Y247568D03*
X190817Y331786D03*
X189761Y421732D03*
X190553Y506517D03*
X192888Y598130D03*
X190816Y681645D03*
X191846Y774526D03*
X191606Y856244D03*
X196311Y947202D03*
X195516Y1032544D03*
X191250Y1122856D03*
X191342Y1206233D03*
X191846Y1299104D03*
X190552Y1380966D03*
X189463Y1474162D03*
X191079Y1557277D03*
X192143Y1648177D03*
X191607Y1731351D03*
X191530Y1823227D03*
X190289Y1900420D03*
X192125Y1998730D03*
X191530Y2043388D03*
G54D20*
X20468Y696341D03*
Y984333D03*
X20472Y1054606D03*
Y1342598D03*
G54D11*
X25219Y18752D03*
X3001Y52034D03*
Y100034D03*
Y150034D03*
Y200034D03*
Y250034D03*
Y300034D03*
Y350034D03*
Y400034D03*
Y450034D03*
Y500034D03*
Y550034D03*
X11677Y578766D03*
X3001Y600034D03*
Y650034D03*
Y700034D03*
Y750034D03*
Y800034D03*
Y850034D03*
Y900034D03*
Y950034D03*
Y1000034D03*
Y1050034D03*
Y1100034D03*
Y1150034D03*
Y1200034D03*
Y1250034D03*
Y1300034D03*
Y1350034D03*
Y1400034D03*
Y1450034D03*
Y1500034D03*
Y1550034D03*
X16484Y1552159D03*
X11085Y1552589D03*
X3006Y1594602D03*
X3012Y1610165D03*
X3001Y1650034D03*
Y1700034D03*
Y1750034D03*
Y1800034D03*
Y1850034D03*
Y1900034D03*
Y1950034D03*
Y2000034D03*
Y2050034D03*
X48433Y866179D03*
X48467Y869278D03*
X26833Y2067866D03*
X58750Y579653D03*
X63820Y579654D03*
X60815Y1019026D03*
X63577Y1019115D03*
X59127Y1257647D03*
X57458Y1253378D03*
X58356Y1279812D03*
X58416Y1272383D03*
X54543Y1296513D03*
X63061Y1296312D03*
X67568Y1296654D03*
X54108Y1559138D03*
X75219Y18752D03*
X97417Y32853D03*
Y37438D03*
X97536Y376580D03*
X97457Y371909D03*
X97985Y391220D03*
X97643Y396024D03*
X93223Y417736D03*
X94347Y421562D03*
X98591Y720745D03*
X98564Y715937D03*
X97443Y739962D03*
X97534Y735248D03*
X98124Y745139D03*
X76446Y1014871D03*
X79499D03*
X96904Y1067515D03*
X96948Y1092036D03*
X96949Y1087095D03*
X96774Y1072226D03*
X75475Y1315303D03*
X97403Y1424340D03*
X97825Y1419492D03*
X96993Y1443743D03*
X96996Y1438980D03*
X97465Y1447919D03*
X95236Y1453321D03*
X76833Y2067866D03*
X106335Y22580D03*
X108082Y38899D03*
X102646Y49461D03*
X101430Y41803D03*
X104350Y62293D03*
X107263Y72244D03*
X109054Y58250D03*
X104116Y82557D03*
X107213Y85169D03*
X105451Y406795D03*
X114498Y396207D03*
X101990Y426104D03*
X109475Y434743D03*
X111017Y419566D03*
X105087Y754126D03*
X101244Y774100D03*
X112836Y769122D03*
X113697Y794293D03*
X105395Y972040D03*
X102611Y972220D03*
X98652Y1096403D03*
X108779Y1105760D03*
X112503Y1115860D03*
X105684Y1125919D03*
X108468Y1129286D03*
X105455Y1472894D03*
X108574Y1463389D03*
X113518Y1489571D03*
X99103Y1765722D03*
X99068Y1760827D03*
X99047Y1785571D03*
X98873Y1780542D03*
X99294Y1789947D03*
X107391Y1794460D03*
X105669Y1815227D03*
X108819Y1812118D03*
Y1824470D03*
X109991Y2083607D03*
X125219Y3002D03*
X162384Y56744D03*
X161742Y72497D03*
X162586Y68130D03*
X161339Y88108D03*
X159417Y91281D03*
X158901Y85017D03*
X161377Y407575D03*
X161517Y436119D03*
X161257Y420869D03*
X159019Y439268D03*
X158807Y432969D03*
X161826Y756757D03*
X161131Y774878D03*
X161644Y764231D03*
X158956Y780982D03*
X161479Y784141D03*
X159053Y787280D03*
X164539Y1116135D03*
X162140Y1106853D03*
X159382Y1136151D03*
X158456Y1129045D03*
X163099Y1457084D03*
X162524Y1462651D03*
X162242Y1471380D03*
X159216Y1477124D03*
X159526Y1483434D03*
X163250Y1815631D03*
X162140Y1807740D03*
X161844Y1828225D03*
X159822Y1831380D03*
X159075Y1825087D03*
X159991Y2083607D03*
X175219Y3002D03*
X184284Y948331D03*
X184196Y967371D03*
X184632Y983423D03*
X184353Y1001556D03*
X184118Y1019280D03*
X188385Y1020810D03*
X209991Y2083607D03*
X225219Y3002D03*
X267627Y115559D03*
X259991Y2083607D03*
X275219Y3002D03*
X287420Y162540D03*
X276617Y241400D03*
X285513Y337688D03*
X286665Y417844D03*
X274991Y463099D03*
X282776Y512341D03*
X273938D03*
X290984Y592215D03*
X274514Y687192D03*
X283340D03*
X278184Y767643D03*
X270070Y812192D03*
X276686Y862488D03*
X285788Y862237D03*
X281194Y941442D03*
X285666Y1031162D03*
X288188Y1116146D03*
X284194Y1206777D03*
X289210Y1290634D03*
X284240Y1389544D03*
X275052Y1389715D03*
X275521Y1464435D03*
X289675Y1558211D03*
X289421Y1641558D03*
X279703Y1738398D03*
X289499Y1738735D03*
X286623Y1814400D03*
X287121Y1913327D03*
X278262D03*
X299687Y63778D03*
X308651D03*
X296523Y162585D03*
X294506Y337688D03*
X294617Y1031162D03*
X293807Y1206777D03*
X313894Y1513883D03*
X298870Y1558211D03*
X292614Y1864565D03*
X293606Y1858668D03*
X309991Y2083607D03*
X325219Y3002D03*
X317567Y63778D03*
X325796Y1162266D03*
X323403Y1172804D03*
X320045Y1990215D03*
X359991Y2083607D03*
X375219Y3002D03*
X402512Y17108D03*
Y67108D03*
Y117108D03*
Y167108D03*
Y217108D03*
Y267108D03*
Y317108D03*
Y367108D03*
Y417108D03*
Y467108D03*
Y517108D03*
Y567108D03*
Y617108D03*
Y667108D03*
Y717108D03*
Y767108D03*
Y817108D03*
Y867108D03*
Y917108D03*
Y967108D03*
Y1017108D03*
Y1067108D03*
Y1117108D03*
Y1167108D03*
Y1217108D03*
Y1267108D03*
Y1317108D03*
Y1367108D03*
Y1417108D03*
Y1467108D03*
Y1517108D03*
Y1567108D03*
Y1617108D03*
Y1667108D03*
Y1717108D03*
Y1767108D03*
Y1817108D03*
Y1867108D03*
Y1917108D03*
Y1967108D03*
Y2017108D03*
Y2067108D03*
G54D12*
X12735Y59953D03*
Y181976D03*
Y268811D03*
Y390834D03*
Y1922291D03*
Y2026661D03*
X57735Y59953D03*
Y181976D03*
Y268811D03*
Y390834D03*
Y1922291D03*
Y2026661D03*
G54D30*
X119920Y328071D03*
Y676102D03*
Y1024134D03*
Y1372165D03*
Y1720197D03*
Y2068228D03*
G54D21*
X25389Y1030199D03*
X25393Y1388464D03*
G54D31*
X163385Y27205D03*
Y202205D03*
Y377205D03*
X163386Y552205D03*
Y727205D03*
X163385Y902205D03*
Y1077205D03*
Y1252205D03*
Y1427205D03*
Y1602205D03*
Y1777205D03*
Y1952205D03*
X373385Y32520D03*
Y207520D03*
Y382520D03*
X373386Y557520D03*
Y732520D03*
X373385Y907520D03*
Y1082520D03*
Y1257520D03*
Y1432520D03*
Y1607520D03*
Y1782520D03*
Y1957520D03*
G54D13*
X17735Y206976D03*
Y415834D03*
Y1947291D03*
Y2051661D03*
X52735Y34953D03*
Y243811D03*
X203542Y73105D03*
X204069Y152050D03*
X204137Y247568D03*
X204597Y331786D03*
X203541Y421732D03*
X204333Y506517D03*
X206668Y598130D03*
X204596Y681645D03*
X205626Y774526D03*
X205386Y856244D03*
X210091Y947202D03*
X209296Y1032544D03*
X205030Y1122856D03*
X205122Y1206233D03*
X205626Y1299104D03*
X204332Y1380966D03*
X203243Y1474162D03*
X204859Y1557277D03*
X205923Y1648177D03*
X205387Y1731351D03*
X205310Y1823227D03*
X204069Y1900420D03*
X205905Y1998730D03*
X205310Y2043388D03*
G54D22*
X18995Y1612992D03*
X53995Y518701D03*
G54D32*
X173385Y32520D03*
Y207520D03*
Y382520D03*
X173386Y557520D03*
Y732520D03*
X173385Y907520D03*
Y1082520D03*
Y1257520D03*
Y1432520D03*
Y1607520D03*
Y1782520D03*
Y1957520D03*
G54D23*
X23402Y1668874D03*
Y1685410D03*
Y1701945D03*
Y1718480D03*
Y1735016D03*
Y1751551D03*
Y1768087D03*
Y1784622D03*
Y1817693D03*
Y1801158D03*
X45056Y1668874D03*
Y1685410D03*
Y1701945D03*
Y1718480D03*
Y1735016D03*
Y1751551D03*
Y1768087D03*
Y1784622D03*
Y1801158D03*
G54D14*
X18995Y508701D03*
X23995Y518701D03*
X21495Y559882D03*
X11692D03*
X21495Y1571811D03*
X11692D03*
X23995Y1622992D03*
X28995Y508701D03*
X38995D03*
X48995D03*
X33995Y518701D03*
X43995D03*
X51495Y559882D03*
Y1571811D03*
X43995Y1622992D03*
X33995D03*
X48995Y1612992D03*
X38995D03*
X28995D03*
X61298Y559882D03*
Y1571811D03*
X53995Y1622992D03*
G54D15*
X13995Y543701D03*
Y1587992D03*
X58995Y543701D03*
Y1587992D03*
G54D33*
X173385Y21890D03*
X183385Y32520D03*
Y21890D03*
X193385Y32520D03*
Y21890D03*
X173385Y196890D03*
X183385D03*
X193385D03*
X183385Y207520D03*
X193385D03*
X173385Y371890D03*
X183385D03*
X193385D03*
X183385Y382520D03*
X193385D03*
X173386Y546890D03*
X183386Y557520D03*
Y546890D03*
X193386Y557520D03*
Y546890D03*
X173386Y721890D03*
X183386Y732520D03*
Y721890D03*
X193386Y732520D03*
Y721890D03*
X173385Y896890D03*
X183385D03*
X193385D03*
X183385Y907520D03*
X193385D03*
X173385Y1071890D03*
X183385D03*
X193385D03*
X183385Y1082520D03*
X193385D03*
X173385Y1246890D03*
X183385Y1257520D03*
Y1246890D03*
X193385Y1257520D03*
Y1246890D03*
X173385Y1421890D03*
X183385Y1432520D03*
Y1421890D03*
X193385Y1432520D03*
Y1421890D03*
X173385Y1596890D03*
X183385D03*
X193385D03*
X183385Y1607520D03*
X193385D03*
X173385Y1771890D03*
X183385D03*
X193385D03*
X183385Y1782520D03*
X193385D03*
X173385Y1946890D03*
X183385Y1957520D03*
Y1946890D03*
X193385Y1957520D03*
Y1946890D03*
X203385Y32520D03*
Y21890D03*
X213385Y32520D03*
Y21890D03*
X203385Y196890D03*
X213385D03*
X203385Y207520D03*
X213385D03*
X203385Y371890D03*
X213385D03*
X203385Y382520D03*
X213385D03*
X203386Y557520D03*
Y546890D03*
X213386Y557520D03*
Y546890D03*
X203386Y732520D03*
Y721890D03*
X213386Y732520D03*
Y721890D03*
X203385Y896890D03*
X213385D03*
X203385Y907520D03*
X213385D03*
X203385Y1071890D03*
X213385D03*
X203385Y1082520D03*
X213385D03*
X203385Y1257520D03*
Y1246890D03*
X213385Y1257520D03*
Y1246890D03*
X203385Y1432520D03*
Y1421890D03*
X213385Y1432520D03*
Y1421890D03*
X203385Y1596890D03*
X213385D03*
X203385Y1607520D03*
X213385D03*
X203385Y1771890D03*
X213385D03*
X203385Y1782520D03*
X213385D03*
X203385Y1957520D03*
Y1946890D03*
X213385Y1957520D03*
Y1946890D03*
X223385Y32520D03*
Y21890D03*
X233385Y32520D03*
Y21890D03*
X243385Y32520D03*
Y21890D03*
X223385Y196890D03*
X233385D03*
X243385D03*
X223385Y207520D03*
X233385D03*
X243385D03*
X223385Y371890D03*
X233385D03*
X243385D03*
X223385Y382520D03*
X233385D03*
X243385D03*
X223386Y557520D03*
Y546890D03*
X233386Y557520D03*
Y546890D03*
X243386Y557520D03*
Y546890D03*
X223386Y732520D03*
Y721890D03*
X233386Y732520D03*
Y721890D03*
X243386Y732520D03*
Y721890D03*
X223385Y896890D03*
X233385D03*
X243385D03*
X223385Y907520D03*
X233385D03*
X243385D03*
X223385Y1071890D03*
X233385D03*
X243385D03*
X223385Y1082520D03*
X233385D03*
X243385D03*
X223385Y1257520D03*
Y1246890D03*
X233385Y1257520D03*
Y1246890D03*
X243385Y1257520D03*
Y1246890D03*
X223385Y1432520D03*
Y1421890D03*
X233385Y1432520D03*
Y1421890D03*
X243385Y1432520D03*
Y1421890D03*
X223385Y1596890D03*
X233385D03*
X243385D03*
X223385Y1607520D03*
X233385D03*
X243385D03*
X223385Y1771890D03*
X233385D03*
X243385D03*
X223385Y1782520D03*
X233385D03*
X243385D03*
X223385Y1957520D03*
Y1946890D03*
X233385Y1957520D03*
Y1946890D03*
X243385Y1957520D03*
Y1946890D03*
X253385Y21890D03*
Y32520D03*
X263385Y21890D03*
Y32520D03*
X253385Y196890D03*
X263385D03*
X253385Y207520D03*
X263385D03*
X253385Y371890D03*
X263385D03*
X253385Y382520D03*
X263385D03*
X253386Y546890D03*
Y557520D03*
X263386Y546890D03*
Y557520D03*
X253386Y721890D03*
Y732520D03*
X263386Y721890D03*
Y732520D03*
X253385Y896890D03*
X263385D03*
X253385Y907520D03*
X263385D03*
X253385Y1071890D03*
X263385D03*
X253385Y1082520D03*
X263385D03*
X253385Y1246890D03*
Y1257520D03*
X263385Y1246890D03*
Y1257520D03*
X253385Y1421890D03*
Y1432520D03*
X263385Y1421890D03*
Y1432520D03*
X253385Y1596890D03*
X263385D03*
X253385Y1607520D03*
X263385D03*
X253385Y1771890D03*
X263385D03*
X253385Y1782520D03*
X263385D03*
X253385Y1946890D03*
Y1957520D03*
X263385Y1946890D03*
Y1957520D03*
X273385Y21890D03*
Y32520D03*
X283385Y21890D03*
Y32520D03*
X273385Y196890D03*
X283385D03*
X273385Y207520D03*
X283385D03*
X273385Y371890D03*
X283385D03*
X273385Y382520D03*
X283385D03*
X273386Y546890D03*
Y557520D03*
X283386Y546890D03*
Y557520D03*
X273386Y721890D03*
Y732520D03*
X283386Y721890D03*
Y732520D03*
X273385Y896890D03*
X283385D03*
X273385Y907520D03*
X283385D03*
X273385Y1071890D03*
X283385D03*
X273385Y1082520D03*
X283385D03*
X273385Y1246890D03*
Y1257520D03*
X283385Y1246890D03*
Y1257520D03*
X273385Y1421890D03*
Y1432520D03*
X283385Y1421890D03*
Y1432520D03*
X273385Y1596890D03*
X283385D03*
X273385Y1607520D03*
X283385D03*
X273385Y1771890D03*
X283385D03*
X273385Y1782520D03*
X283385D03*
X273385Y1946890D03*
Y1957520D03*
X283385Y1946890D03*
Y1957520D03*
X293385Y21890D03*
Y32520D03*
X303385Y21890D03*
Y32520D03*
X313385D03*
Y21890D03*
X293385Y196890D03*
X303385D03*
X313385D03*
X293385Y207520D03*
X303385D03*
X313385D03*
X293385Y371890D03*
X303385D03*
X313385D03*
X293385Y382520D03*
X303385D03*
X313385D03*
X293386Y546890D03*
Y557520D03*
X303386Y546890D03*
Y557520D03*
X313386D03*
Y546890D03*
X293386Y721890D03*
Y732520D03*
X303386Y721890D03*
Y732520D03*
X313386D03*
Y721890D03*
X293385Y896890D03*
X303385D03*
X313385D03*
X293385Y907520D03*
X303385D03*
X313385D03*
X293385Y1071890D03*
X303385D03*
X313385D03*
X293385Y1082520D03*
X303385D03*
X313385D03*
X293385Y1246890D03*
Y1257520D03*
X303385Y1246890D03*
Y1257520D03*
X313385D03*
Y1246890D03*
X293385Y1421890D03*
Y1432520D03*
X303385Y1421890D03*
Y1432520D03*
X313385D03*
Y1421890D03*
X293385Y1596890D03*
X303385D03*
X313385D03*
X293385Y1607520D03*
X303385D03*
X313385D03*
X293385Y1771890D03*
X303385D03*
X313385D03*
X293385Y1782520D03*
X303385D03*
X313385D03*
X293385Y1946890D03*
Y1957520D03*
X303385Y1946890D03*
Y1957520D03*
X313385D03*
Y1946890D03*
X337165Y24705D03*
X323385Y32520D03*
Y21890D03*
X337165Y34705D03*
Y199705D03*
X323385Y196890D03*
X337165Y209705D03*
X323385Y207520D03*
Y371890D03*
X337165Y374705D03*
Y384705D03*
X323385Y382520D03*
X337166Y549705D03*
Y559705D03*
X323386Y557520D03*
Y546890D03*
X337166Y724705D03*
X323386Y732520D03*
Y721890D03*
X337166Y734705D03*
X337165Y899705D03*
X323385Y896890D03*
X337165Y909705D03*
X323385Y907520D03*
Y1071890D03*
X337165Y1074705D03*
Y1084705D03*
X323385Y1082520D03*
X337165Y1249705D03*
Y1259705D03*
X323385Y1257520D03*
Y1246890D03*
X337165Y1424705D03*
Y1434705D03*
X323385Y1432520D03*
Y1421890D03*
X337165Y1599705D03*
X323385Y1596890D03*
X337165Y1609705D03*
X323385Y1607520D03*
Y1771890D03*
X337165Y1774705D03*
Y1784705D03*
X323385Y1782520D03*
X337165Y1949705D03*
Y1959705D03*
X323385Y1957520D03*
Y1946890D03*
X342165Y19705D03*
Y29705D03*
X347165Y24705D03*
X352165Y19705D03*
Y29705D03*
X357165Y24705D03*
X362165Y19705D03*
Y29705D03*
X347165Y34705D03*
X357165D03*
X342165Y194705D03*
X347165Y199705D03*
X352165Y194705D03*
X357165Y199705D03*
X362165Y194705D03*
X342165Y204705D03*
X347165Y209705D03*
X352165Y204705D03*
X357165Y209705D03*
X362165Y204705D03*
X342165Y369705D03*
X352165D03*
X362165D03*
X342165Y379705D03*
X347165Y374705D03*
Y384705D03*
X352165Y379705D03*
X357165Y374705D03*
Y384705D03*
X362165Y379705D03*
X342166Y544705D03*
Y554705D03*
X347166Y549705D03*
Y559705D03*
X352166Y544705D03*
Y554705D03*
X357166Y549705D03*
Y559705D03*
X362166Y544705D03*
Y554705D03*
X342166Y719705D03*
Y729705D03*
X347166Y724705D03*
X352166Y719705D03*
Y729705D03*
X357166Y724705D03*
X362166Y719705D03*
Y729705D03*
X347166Y734705D03*
X357166D03*
X342165Y894705D03*
X347165Y899705D03*
X352165Y894705D03*
X357165Y899705D03*
X362165Y894705D03*
X342165Y904705D03*
X347165Y909705D03*
X352165Y904705D03*
X357165Y909705D03*
X362165Y904705D03*
X342165Y1069705D03*
X352165D03*
X362165D03*
X342165Y1079705D03*
X347165Y1074705D03*
Y1084705D03*
X352165Y1079705D03*
X357165Y1074705D03*
Y1084705D03*
X362165Y1079705D03*
X342165Y1244705D03*
Y1254705D03*
X347165Y1249705D03*
Y1259705D03*
X352165Y1244705D03*
Y1254705D03*
X357165Y1249705D03*
Y1259705D03*
X362165Y1244705D03*
Y1254705D03*
X342165Y1419705D03*
Y1429705D03*
X347165Y1424705D03*
Y1434705D03*
X352165Y1419705D03*
Y1429705D03*
X357165Y1424705D03*
Y1434705D03*
X362165Y1419705D03*
Y1429705D03*
X342165Y1594705D03*
X347165Y1599705D03*
X352165Y1594705D03*
X357165Y1599705D03*
X362165Y1594705D03*
X342165Y1604705D03*
X347165Y1609705D03*
X352165Y1604705D03*
X357165Y1609705D03*
X362165Y1604705D03*
X342165Y1769705D03*
X352165D03*
X362165D03*
X342165Y1779705D03*
X347165Y1774705D03*
Y1784705D03*
X352165Y1779705D03*
X357165Y1774705D03*
Y1784705D03*
X362165Y1779705D03*
X342165Y1944705D03*
Y1954705D03*
X347165Y1949705D03*
Y1959705D03*
X352165Y1944705D03*
Y1954705D03*
X357165Y1949705D03*
Y1959705D03*
X362165Y1944705D03*
Y1954705D03*
G54D24*
X49441Y1238962D03*
X46980Y1335843D03*
Y1325843D03*
Y1315843D03*
Y1320843D03*
Y1330843D03*
Y1345843D03*
Y1340843D03*
X61888Y666012D03*
X57124Y675327D03*
X54483Y679810D03*
X59236Y670758D03*
X70865Y854278D03*
Y872278D03*
Y866278D03*
Y860278D03*
Y897750D03*
Y890116D03*
X61866Y1309190D03*
X67568Y1307829D03*
X54543Y1308995D03*
X61866Y1342104D03*
X95775Y751469D03*
X92216Y899865D03*
X90708Y878615D03*
X92633Y907404D03*
X92989Y927334D03*
X98139Y990959D03*
X82763Y1060051D03*
X96684Y1081791D03*
X96510Y1395382D03*
X106958Y26285D03*
X107405Y49898D03*
X107037Y34687D03*
X106836Y376461D03*
X106709Y391219D03*
X107025Y725368D03*
X106935Y745139D03*
X107173Y735219D03*
X100687Y999391D03*
X107351Y1093484D03*
X107235Y1081791D03*
X107215Y1072208D03*
X105152Y1118381D03*
X100719Y1312810D03*
Y1306810D03*
Y1330810D03*
Y1336810D03*
Y1324810D03*
Y1318810D03*
Y1346065D03*
X101626Y1397635D03*
X106962Y1434041D03*
X106921Y1419492D03*
X106763Y1444599D03*
X107006Y1452651D03*
X107355Y1770437D03*
X107220Y1791589D03*
X107373Y1780544D03*
X106819Y1802230D03*
X144878Y1738861D03*
X157558Y51426D03*
X156865Y401207D03*
X156610Y751063D03*
X156854Y1101031D03*
X158618Y1399448D03*
X164037Y1400226D03*
X170351Y1401324D03*
X159192Y1451105D03*
X150309Y1737009D03*
X168151Y1739208D03*
X156183Y1735240D03*
X165782Y1732903D03*
X163257Y1737619D03*
X156452Y1800821D03*
X175989Y944537D03*
X176011Y936829D03*
X175359Y963486D03*
X175561Y955964D03*
X175135Y972490D03*
X175022Y980281D03*
X175742Y989958D03*
X175449Y997660D03*
X175698Y1008730D03*
X175473Y1016296D03*
X175448Y1031766D03*
X175897Y1023997D03*
X176083Y1402321D03*
X173394Y1736051D03*
X256947Y128276D03*
X257125Y115559D03*
X265722Y463102D03*
X265737Y473680D03*
X255837Y823626D03*
X255687Y812192D03*
X283086Y162675D03*
X271547Y245353D03*
X281193Y241624D03*
X281074Y337688D03*
X289895D03*
X291002Y417844D03*
X281569Y421169D03*
X278405Y512341D03*
X269516D03*
X285348Y595540D03*
X270109Y687192D03*
X278955D03*
X273114Y770968D03*
X282737Y767643D03*
X272181Y862354D03*
X281305Y862237D03*
X275966Y944767D03*
X285874Y941442D03*
X281124Y1031162D03*
X290107D03*
X282958Y1119471D03*
X289082Y1206777D03*
X279559D03*
X283808Y1293959D03*
X279518Y1389543D03*
X270579Y1389626D03*
X270234Y1467760D03*
X279990Y1464435D03*
X285054Y1558211D03*
X284086Y1644883D03*
X274704Y1738196D03*
X284583Y1738465D03*
X281066Y1819569D03*
X291550Y1814846D03*
X280240Y1858668D03*
X279976Y1864565D03*
X282717Y1913327D03*
X273817D03*
X304151Y63778D03*
X313089D03*
X294483Y67732D03*
X291943Y162630D03*
X308057Y248863D03*
X306267Y241010D03*
X314914Y238162D03*
X314940Y252083D03*
X305867Y258589D03*
X295509Y592215D03*
X309678Y1053262D03*
X292698Y1116146D03*
X312527Y1162266D03*
X312698Y1172804D03*
X294133Y1290634D03*
X314183Y1403423D03*
X302267Y1524401D03*
X301734Y1513883D03*
X312077Y1575871D03*
X294392Y1558211D03*
X294090Y1641558D03*
X311539Y1753499D03*
X314562Y1994087D03*
X331403Y51409D03*
X333889Y56021D03*
X338227Y61559D03*
X322005Y63778D03*
X320372Y225979D03*
X318088Y231820D03*
X321899Y238137D03*
X329930Y245684D03*
X331046Y232021D03*
X320961Y250105D03*
X324709Y231580D03*
X335522Y404033D03*
X323313Y418313D03*
X326196Y413982D03*
X328950Y409216D03*
X320980Y423225D03*
X336617Y577978D03*
X319305Y582111D03*
X329636Y584715D03*
X317724Y588250D03*
X337387Y586230D03*
X320380Y576491D03*
X331867Y589810D03*
X333750Y595326D03*
X323751Y589155D03*
X319852Y593330D03*
X321742Y599041D03*
X331568Y752967D03*
X339012Y752859D03*
X329336Y762693D03*
X334010Y758588D03*
X327524Y758020D03*
X339615Y926357D03*
X329938Y948756D03*
X332527Y943746D03*
X324098Y946104D03*
X318557Y941178D03*
X323868Y929978D03*
X326646Y939788D03*
X333300Y928464D03*
X336160Y937262D03*
X328583Y933262D03*
X321425Y951577D03*
X324246Y1051786D03*
X335677Y1048904D03*
X317592Y1053050D03*
X331920Y1116088D03*
X337509Y1109598D03*
X328989Y1121090D03*
X326558Y1126368D03*
X327452Y1279447D03*
X321978Y1282086D03*
X338047Y1282599D03*
X333242Y1276809D03*
X329619Y1284016D03*
X327932Y1289221D03*
X319404Y1401346D03*
X325636Y1399114D03*
X334646Y1400804D03*
X323720Y1570924D03*
X329399Y1571939D03*
X317243Y1574832D03*
X333474Y1566686D03*
X335963Y1573797D03*
X329887Y1752081D03*
X321283Y1753466D03*
X335730Y1753270D03*
X338309Y1927623D03*
X332399Y1926787D03*
X324803Y1990272D03*
X359931Y52189D03*
X348289Y50863D03*
X345089Y56190D03*
X340373Y51579D03*
X342097Y401684D03*
X363825Y401768D03*
X342900Y580126D03*
X362577Y752783D03*
X344109Y751809D03*
X343656Y933725D03*
X345578Y1047844D03*
X344099Y1106798D03*
X349855Y1104302D03*
X344130Y1401670D03*
X350690Y1403243D03*
X348710Y1570187D03*
X361011Y1568890D03*
X343402Y1572080D03*
X348245Y1575241D03*
X355364Y1570990D03*
X345537Y1916558D03*
X344402Y1911123D03*
X363361Y1918313D03*
X358318Y1920680D03*
X363411Y1923459D03*
X340336Y1922409D03*
X347676Y1922165D03*
X372204Y56126D03*
X365720Y52336D03*
X379257Y52158D03*
X379572Y58441D03*
X387524Y76847D03*
X374442Y406857D03*
X380619Y410112D03*
X380878Y403999D03*
X374542Y401282D03*
X368907Y404308D03*
X376654Y754748D03*
X382892Y767710D03*
X386790Y774338D03*
X380186Y761742D03*
X379335Y1189778D03*
X383276Y1184136D03*
X386816Y1179841D03*
X376472Y1194999D03*
X373674Y1199967D03*
X371523Y1204725D03*
X367829Y1566108D03*
X374775Y1919243D03*
X379403Y1917261D03*
X369748Y1921795D03*
X391278Y765894D03*
G54D34*
X307086Y308267D03*
G54D25*
X45056Y1817693D03*
G54D16*
X5491Y528544D03*
Y1603149D03*
X67499Y528544D03*
Y1603149D03*
G54D35*
X307086Y1883071D03*
G54D17*
X17480Y599901D03*
Y627264D03*
Y1471949D03*
Y1499311D03*
G54D26*
X65354Y101180D03*
X55511Y105117D03*
X51574Y114960D03*
X55511Y124803D03*
X65354Y128740D03*
Y451180D03*
X55511Y455117D03*
X51574Y464960D03*
X55511Y474803D03*
X65354Y478740D03*
Y801180D03*
X55511Y805117D03*
X51574Y814960D03*
X55511Y824803D03*
X65354Y828740D03*
Y1151180D03*
X55511Y1155117D03*
X51574Y1164960D03*
X55511Y1174803D03*
X65354Y1178740D03*
Y1501180D03*
X55511Y1505117D03*
X51574Y1514960D03*
X55511Y1524803D03*
X65354Y1528740D03*
Y1851180D03*
X55511Y1855117D03*
X51574Y1864960D03*
X55511Y1874803D03*
X65354Y1878740D03*
X75197Y105117D03*
Y124803D03*
X79134Y114960D03*
Y464960D03*
X75197Y455117D03*
Y474803D03*
Y805117D03*
Y824803D03*
X79134Y814960D03*
Y1164960D03*
X75197Y1155117D03*
Y1174803D03*
Y1505117D03*
Y1524803D03*
X79134Y1514960D03*
Y1864960D03*
X75197Y1855117D03*
Y1874803D03*
X307086Y113385D03*
X297243Y117322D03*
X293306Y127165D03*
X297243Y137008D03*
X307086Y140945D03*
Y463385D03*
X297243Y467322D03*
X293306Y477165D03*
X297243Y487008D03*
X307086Y490945D03*
Y813385D03*
X297243Y817322D03*
X293306Y827165D03*
X297243Y837008D03*
X307086Y840945D03*
Y1329724D03*
X297243Y1333661D03*
X293306Y1343504D03*
X297243Y1353347D03*
X307086Y1357284D03*
Y1679724D03*
X297243Y1683661D03*
X293306Y1693504D03*
X297243Y1703347D03*
X307086Y1707284D03*
X307087Y2029723D03*
X297244Y2033660D03*
X293307Y2043503D03*
X297244Y2053346D03*
X307087Y2057283D03*
X320866Y127165D03*
X316929Y117322D03*
Y137008D03*
Y467322D03*
Y487008D03*
X320866Y477165D03*
Y827165D03*
X316929Y817322D03*
Y837008D03*
Y1333661D03*
Y1353347D03*
X320866Y1343504D03*
Y1693504D03*
X316929Y1683661D03*
Y1703347D03*
X316930Y2033660D03*
Y2053346D03*
X320867Y2043503D03*
G54D27*
X65354Y114960D03*
Y464960D03*
Y814960D03*
Y1164960D03*
Y1514960D03*
Y1864960D03*
X307086Y127165D03*
Y477165D03*
Y827165D03*
Y1343504D03*
Y1693504D03*
X307087Y2043503D03*
G54D36*
X359842Y78780D03*
Y253780D03*
Y428779D03*
Y603779D03*
Y778780D03*
Y953780D03*
Y1128779D03*
Y1303780D03*
Y1478780D03*
Y1653780D03*
Y1828779D03*
Y2003780D03*
G54D18*
X9606Y599901D03*
Y627264D03*
Y1471949D03*
Y1499311D03*
G54D37*
G01X60815Y1019026D02*
Y1091102D01*
X75814Y1106101D01*
Y1123344D01*
X96579Y1144109D01*
Y1252553D01*
X79344Y1269788D01*
Y1411288D01*
X86507Y1418451D01*
Y1493650D01*
X95767Y1502910D01*
Y1750829D01*
X92185Y1754411D01*
Y1814887D01*
X110828Y1833530D01*
X147562D01*
X149712Y1831380D01*
X159822D01*
G01X63577Y1019115D02*
Y1089957D01*
X78576Y1104956D01*
Y1122199D01*
X99341Y1142964D01*
Y1253698D01*
X82106Y1270933D01*
Y1410143D01*
X89269Y1417306D01*
Y1492505D01*
X98529Y1501765D01*
Y1751974D01*
X94947Y1755556D01*
Y1810598D01*
X108819Y1824470D01*
G01X109475Y434743D02*
X98132Y446086D01*
Y677235D01*
X129426Y708529D01*
X142633D01*
X146386Y712282D01*
Y735259D01*
X166489Y755362D01*
Y791181D01*
X148493Y809177D01*
X115243D01*
X106501Y817919D01*
Y949470D01*
X116031Y959000D01*
X149273D01*
X151627Y961354D01*
X173227D01*
X175359Y963486D01*
G01X76446Y1014871D02*
Y1086348D01*
X90731Y1100633D01*
Y1118368D01*
X109480Y1137117D01*
X158416D01*
X159382Y1136151D01*
G01X108468Y1129286D02*
X105523D01*
X93376Y1117139D01*
Y1098960D01*
X79499Y1085083D01*
Y1014871D01*
G01X175989Y944537D02*
X173869Y942417D01*
X150455D01*
X147070Y939032D01*
X117293D01*
X112488Y934227D01*
Y834385D01*
X117608Y829265D01*
X142893D01*
X145887Y826271D01*
Y822211D01*
X173995Y794103D01*
Y753606D01*
X152883Y732494D01*
Y708966D01*
X145652Y701735D01*
X132220D01*
X108160Y677675D01*
Y449463D01*
X116359Y441264D01*
X152160D01*
X153775Y442879D01*
X160668D01*
X165000Y438547D01*
Y397209D01*
X150192Y382401D01*
Y366253D01*
X138635Y354696D01*
X131704D01*
X106080Y329072D01*
Y94908D01*
X107213Y93775D01*
Y85169D01*
G01X176011Y936829D02*
X173717Y939123D01*
X154130D01*
X144310Y929303D01*
X118237D01*
X115244Y926310D01*
Y841630D01*
X117922Y838952D01*
X143526D01*
X149826Y832652D01*
Y822931D01*
X177289Y795468D01*
Y752241D01*
X155802Y730754D01*
Y707238D01*
X146360Y697796D01*
X133006D01*
X111501Y676291D01*
Y455772D01*
X116122Y451151D01*
X157241D01*
X167864Y440528D01*
Y396022D01*
X153056Y381214D01*
Y365066D01*
X139822Y351832D01*
X132891D01*
X108944Y327885D01*
Y97915D01*
X113720Y93139D01*
X157559D01*
X159417Y91281D01*
G01X175561Y955964D02*
X173854Y957671D01*
X152906D01*
X144704Y949469D01*
X117648D01*
X109415Y941236D01*
Y824931D01*
X114929Y819417D01*
X143462D01*
X170172Y792707D01*
Y753836D01*
X149583Y733247D01*
Y710118D01*
X144311Y704846D01*
X130487D01*
X101683Y676042D01*
Y447433D01*
X118066Y431050D01*
X150801D01*
X159019Y439268D01*
G01X159053Y787280D02*
X147092Y799241D01*
X117816D01*
X103584Y813473D01*
Y969160D01*
X105395Y970971D01*
Y972040D01*
G01X102611Y972220D02*
X100812Y970421D01*
Y807178D01*
X113697Y794293D01*
G01X175448Y1031766D02*
X173134Y1029452D01*
X160796D01*
X153758Y1036490D01*
Y1086911D01*
X172350Y1105503D01*
Y1131699D01*
X147018Y1157031D01*
X117645D01*
X113432Y1161244D01*
Y1380741D01*
X126508Y1393817D01*
X149194D01*
X155490Y1400113D01*
Y1479398D01*
X159526Y1483434D01*
G01X175897Y1023997D02*
X173494Y1026400D01*
X159531D01*
X150706Y1035225D01*
Y1088176D01*
X169298Y1106768D01*
Y1130434D01*
X152548Y1147184D01*
X117686D01*
X110591Y1154279D01*
Y1381918D01*
X124499Y1395826D01*
X124500D01*
X126195Y1397521D01*
X147384D01*
X152438Y1402575D01*
Y1475082D01*
X142533Y1484987D01*
X118102D01*
X113518Y1489571D01*
G54D28*
X55158Y882277D03*
X344826Y2035270D03*
X389572Y66182D03*
G54D19*
X15547Y707364D03*
X25389D03*
X7673Y703427D03*
X15547Y715238D03*
Y723112D03*
Y730986D03*
X25389Y715238D03*
Y723112D03*
Y730986D03*
X7673Y711301D03*
Y719175D03*
Y727049D03*
X15547Y738860D03*
Y746734D03*
Y754608D03*
X25389Y738860D03*
Y746734D03*
Y754608D03*
X7673Y734923D03*
Y742797D03*
Y750671D03*
Y758545D03*
X15547Y762483D03*
Y770357D03*
Y778231D03*
X25389Y762483D03*
Y770357D03*
Y778231D03*
X7673Y766419D03*
Y774293D03*
Y782167D03*
X15547Y786105D03*
Y793979D03*
Y801853D03*
X25389Y786105D03*
Y793979D03*
Y801853D03*
X7673Y790041D03*
Y797915D03*
Y805790D03*
X15547Y809727D03*
Y817601D03*
Y825475D03*
X25389Y809727D03*
Y817601D03*
Y825475D03*
X7673Y813664D03*
Y821538D03*
Y829412D03*
X15547Y833349D03*
Y841223D03*
Y849097D03*
X25389Y833349D03*
Y841223D03*
Y849097D03*
X7673Y837286D03*
Y845160D03*
Y853034D03*
X15547Y856971D03*
Y864845D03*
Y872719D03*
X25389Y856971D03*
Y864845D03*
Y872719D03*
X7673Y860908D03*
Y868782D03*
Y876656D03*
X15547Y880593D03*
Y888467D03*
Y896341D03*
X25389Y880593D03*
Y888467D03*
Y896341D03*
X7673Y884530D03*
Y892404D03*
Y900278D03*
X15547Y904215D03*
Y912089D03*
Y919963D03*
X25389Y904215D03*
Y912089D03*
Y919963D03*
X7673Y908152D03*
Y916026D03*
Y923900D03*
X15547Y927837D03*
Y935711D03*
Y943585D03*
Y951459D03*
X25389Y927837D03*
Y935711D03*
Y943585D03*
Y951459D03*
X7673Y931774D03*
Y939648D03*
Y947522D03*
X15547Y959333D03*
Y967207D03*
Y975081D03*
X25389Y959333D03*
Y967207D03*
Y975081D03*
X7673Y955396D03*
Y963270D03*
Y971144D03*
Y979018D03*
Y994766D03*
X15547Y990829D03*
Y998703D03*
X25389Y990829D03*
Y998703D03*
X7673Y1002640D03*
Y1010514D03*
Y1018388D03*
X15547Y1006577D03*
Y1014451D03*
Y1022325D03*
X25389Y1006577D03*
Y1014451D03*
Y1022325D03*
X7673Y1026262D03*
X15547Y1030199D03*
X15551Y1065629D03*
X25393D03*
X7677Y1061692D03*
Y1069566D03*
X15551Y1073503D03*
Y1081377D03*
Y1089251D03*
X25393Y1073503D03*
Y1081377D03*
Y1089251D03*
X7677Y1077440D03*
Y1085314D03*
Y1093188D03*
X15551Y1097125D03*
Y1104999D03*
Y1112873D03*
Y1120748D03*
X25393Y1097125D03*
Y1104999D03*
Y1112873D03*
Y1120748D03*
X7677Y1101062D03*
Y1108936D03*
Y1116810D03*
X15551Y1128622D03*
Y1136496D03*
Y1144370D03*
X25393Y1128622D03*
Y1136496D03*
Y1144370D03*
X7677Y1124684D03*
Y1132558D03*
Y1140432D03*
X15551Y1152244D03*
Y1160118D03*
Y1167992D03*
X25393Y1152244D03*
Y1160118D03*
Y1167992D03*
X7677Y1148306D03*
Y1156180D03*
Y1164055D03*
X15551Y1175866D03*
Y1183740D03*
Y1191614D03*
X25393Y1175866D03*
Y1183740D03*
Y1191614D03*
X7677Y1171929D03*
Y1179803D03*
Y1187677D03*
X15551Y1199488D03*
Y1207362D03*
Y1215236D03*
X25393Y1199488D03*
Y1207362D03*
Y1215236D03*
X7677Y1195551D03*
Y1203425D03*
Y1211299D03*
X15551Y1223110D03*
Y1230984D03*
Y1238858D03*
X25393Y1223110D03*
Y1230984D03*
Y1238858D03*
X7677Y1219173D03*
Y1227047D03*
Y1234921D03*
X15551Y1246732D03*
Y1254606D03*
Y1262480D03*
X25393Y1246732D03*
Y1254606D03*
Y1262480D03*
X7677Y1242795D03*
Y1250669D03*
Y1258543D03*
X15551Y1270354D03*
Y1278228D03*
Y1286102D03*
X25393Y1270354D03*
Y1278228D03*
Y1286102D03*
X7677Y1266417D03*
Y1274291D03*
Y1282165D03*
X15551Y1293976D03*
Y1301850D03*
Y1309724D03*
X25393Y1293976D03*
Y1301850D03*
Y1309724D03*
X7677Y1290039D03*
Y1297913D03*
Y1305787D03*
Y1313661D03*
X15551Y1317598D03*
Y1325472D03*
Y1333346D03*
X25393Y1317598D03*
Y1325472D03*
Y1333346D03*
X7677Y1321535D03*
Y1329409D03*
Y1337283D03*
Y1353031D03*
Y1360905D03*
X15551Y1349094D03*
Y1356968D03*
X25393Y1349094D03*
Y1356968D03*
X7677Y1368779D03*
Y1376653D03*
Y1384527D03*
X15551Y1364842D03*
Y1372716D03*
Y1380590D03*
X25393Y1364842D03*
Y1372716D03*
Y1380590D03*
X15551Y1388464D03*
X33263Y703427D03*
Y711301D03*
Y719175D03*
Y727049D03*
Y734923D03*
Y742797D03*
Y750671D03*
Y758545D03*
Y766419D03*
Y774293D03*
Y782167D03*
Y790041D03*
Y797915D03*
Y805790D03*
Y813664D03*
Y821538D03*
Y829412D03*
Y837286D03*
Y845160D03*
Y853034D03*
Y860908D03*
Y868782D03*
Y876656D03*
Y884530D03*
Y892404D03*
Y900278D03*
Y908152D03*
Y916026D03*
Y923900D03*
Y931774D03*
Y939648D03*
Y947522D03*
Y955396D03*
Y963270D03*
Y971144D03*
Y979018D03*
Y994766D03*
Y1002640D03*
Y1010514D03*
Y1018388D03*
Y1026262D03*
X33267Y1061692D03*
Y1069566D03*
Y1077440D03*
Y1085314D03*
Y1093188D03*
Y1101062D03*
Y1108936D03*
Y1116810D03*
Y1124684D03*
Y1132558D03*
Y1140432D03*
Y1148306D03*
Y1156180D03*
Y1164055D03*
Y1171929D03*
Y1179803D03*
Y1187677D03*
Y1195551D03*
Y1203425D03*
Y1211299D03*
Y1219173D03*
Y1227047D03*
Y1234921D03*
Y1242795D03*
Y1250669D03*
Y1258543D03*
Y1266417D03*
Y1274291D03*
Y1282165D03*
Y1290039D03*
Y1297913D03*
Y1305787D03*
Y1313661D03*
Y1321535D03*
Y1329409D03*
Y1337283D03*
Y1353031D03*
Y1360905D03*
Y1368779D03*
Y1376653D03*
Y1384527D03*
X166500Y126110D03*
Y118626D03*
Y111407D03*
X166329Y140623D03*
X166500Y132705D03*
X166329Y148066D03*
Y156102D03*
Y163621D03*
X165975Y265783D03*
Y296140D03*
Y286803D03*
Y276298D03*
Y312307D03*
Y303868D03*
X156430Y461714D03*
Y483012D03*
X156259Y490930D03*
X156430Y468933D03*
Y476417D03*
X156259Y513928D03*
Y498373D03*
Y506409D03*
X157272Y604773D03*
Y633416D03*
Y613574D03*
Y624079D03*
Y641144D03*
Y649583D03*
X155444Y822725D03*
X162872D03*
Y830209D03*
X155444D03*
X171524Y844722D03*
Y852165D03*
X162872Y836804D03*
X155444D03*
X162701Y844722D03*
X155273D03*
X162701Y852165D03*
X155273D03*
X171524Y860201D03*
Y867720D03*
X162701Y860201D03*
X155273D03*
X162701Y867720D03*
X155273D03*
X166699Y972924D03*
Y983439D03*
Y993944D03*
X166424Y1011298D03*
Y1003570D03*
Y1019737D03*
X169375Y1176256D03*
Y1190335D03*
Y1183740D03*
X153124Y1176256D03*
X160552D03*
Y1183740D03*
Y1190335D03*
X153124D03*
Y1183740D03*
X160552Y1169037D03*
X153124D03*
X169204Y1198253D03*
X160381D03*
X152953D03*
X155749Y1307733D03*
Y1328753D03*
Y1318248D03*
Y1354257D03*
Y1338090D03*
Y1345818D03*
X154109Y1499221D03*
X161537D03*
Y1506440D03*
X170360D03*
X154109D03*
X153938Y1528437D03*
X154109Y1513924D03*
Y1520519D03*
X170360Y1513924D03*
Y1520519D03*
X161537D03*
Y1513924D03*
X161366Y1528437D03*
X170189D03*
X153938Y1535880D03*
Y1543916D03*
Y1551435D03*
X170189Y1535880D03*
Y1543916D03*
X161366Y1535880D03*
Y1543916D03*
Y1551435D03*
X170189D03*
X158492Y1667763D03*
Y1657248D03*
Y1695333D03*
Y1687605D03*
Y1678268D03*
Y1703772D03*
X152091Y1866003D03*
X159519D03*
X152091Y1880706D03*
Y1887301D03*
X168342Y1880706D03*
Y1887301D03*
X159519D03*
Y1880706D03*
Y1873222D03*
X168342D03*
X152091D03*
X151920Y1902662D03*
Y1910698D03*
X168171Y1902662D03*
Y1910698D03*
X159348Y1902662D03*
Y1910698D03*
X151920Y1895219D03*
X159348D03*
X168171D03*
X151920Y1918217D03*
X159348D03*
X168171D03*
X173928Y126110D03*
Y118626D03*
Y111407D03*
X173757Y140623D03*
X173928Y132705D03*
X173757Y148066D03*
Y156102D03*
Y163621D03*
X175033Y261594D03*
Y268813D03*
Y282892D03*
X174862Y290810D03*
Y298253D03*
X175033Y276297D03*
X174862Y313808D03*
Y306289D03*
X179191Y822725D03*
Y830209D03*
X171695Y822725D03*
Y830209D03*
X179191Y836804D03*
X171695D03*
X179020Y844722D03*
Y852165D03*
Y860201D03*
Y867720D03*
X176871Y1176256D03*
Y1190335D03*
Y1183740D03*
X176700Y1198253D03*
X177856Y1506440D03*
Y1513924D03*
Y1520519D03*
X177685Y1528437D03*
Y1535880D03*
Y1543916D03*
Y1551435D03*
X175838Y1880706D03*
Y1887301D03*
Y1873222D03*
X175667Y1902662D03*
Y1910698D03*
Y1895219D03*
Y1918217D03*
X219214Y1287272D03*
Y1301975D03*
X219349Y1308924D03*
X219214Y1294491D03*
X219178Y1324285D03*
Y1332321D03*
Y1316842D03*
Y1339840D03*
X240955Y56999D03*
Y64483D03*
X240784Y78996D03*
X240955Y71078D03*
X240784Y94475D03*
Y101994D03*
Y86439D03*
X243741Y153964D03*
X222732D03*
X232700D03*
X243741Y170131D03*
Y161692D03*
X222732Y170131D03*
Y161692D03*
X232700Y170131D03*
Y161692D03*
X236537Y244995D03*
X227714Y237776D03*
Y244995D03*
X244033D03*
X236537Y259074D03*
X236366Y266992D03*
Y274435D03*
X227714Y259074D03*
X227543Y266992D03*
Y274435D03*
X244033Y259074D03*
X243862Y266992D03*
Y274435D03*
X236537Y252479D03*
X227714D03*
X244033D03*
X236366Y289990D03*
X227543D03*
X243862D03*
X236366Y282471D03*
X227543D03*
X243862D03*
X239746Y407393D03*
Y396878D03*
Y417898D03*
X232548Y461083D03*
X241371Y482381D03*
X241200Y490299D03*
X232548Y482381D03*
X232377Y490299D03*
X241371Y468302D03*
Y475786D03*
X232548Y468302D03*
Y475786D03*
X241200Y513297D03*
X232377D03*
X241200Y497742D03*
X232377D03*
X241200Y505778D03*
X232377D03*
X230963Y608108D03*
X238391D03*
X230963Y601513D03*
X238391D03*
Y594029D03*
X230963D03*
X230792Y631505D03*
X238220D03*
X230792Y623469D03*
X238220D03*
X230792Y616026D03*
X238220D03*
X230792Y639024D03*
X238220D03*
X243980Y754782D03*
X234012D03*
X243980Y762510D03*
Y770949D03*
X234012Y762510D03*
Y770949D03*
X231339Y959673D03*
X238767D03*
Y967157D03*
Y973752D03*
X231339D03*
Y967157D03*
X238767Y952454D03*
X231339D03*
X238596Y981670D03*
X231168D03*
X238596Y997149D03*
Y989113D03*
X231168Y997149D03*
Y989113D03*
X238596Y1004668D03*
X231168D03*
X238659Y1215296D03*
X231231D03*
X238659Y1207777D03*
Y1199741D03*
X231231Y1207777D03*
Y1199741D03*
X226642Y1287272D03*
Y1301975D03*
X235465D03*
X226777Y1308924D03*
X235600D03*
X242961Y1301975D03*
X243096Y1308924D03*
X226642Y1294491D03*
X235465D03*
X242961D03*
X226606Y1324285D03*
X235429D03*
X226606Y1332321D03*
X235429D03*
X242925Y1324285D03*
Y1332321D03*
X226606Y1316842D03*
X235429D03*
X242925D03*
X226606Y1339840D03*
X235429D03*
X242925D03*
X225131Y1663167D03*
X241382Y1670386D03*
X232559Y1663167D03*
Y1670386D03*
X225131D03*
X241211Y1699826D03*
X241382Y1677870D03*
X241211Y1692383D03*
X241382Y1684465D03*
X232559D03*
Y1677870D03*
X232388Y1692383D03*
Y1699826D03*
X225131Y1684465D03*
Y1677870D03*
X224960Y1692383D03*
Y1699826D03*
X241211Y1715381D03*
Y1707862D03*
X232388D03*
Y1715381D03*
X224960Y1707862D03*
Y1715381D03*
X224573Y2031480D03*
X234541D03*
X224573Y2020965D03*
X234541D03*
X224573Y2059050D03*
X234541Y2051322D03*
Y2059050D03*
X224573Y2041985D03*
Y2051322D03*
X234541Y2041985D03*
Y2067489D03*
X224573D03*
X256566Y54944D03*
X264104D03*
X256566Y45572D03*
X264104D03*
X248451Y56999D03*
X256566Y65449D03*
X264104D03*
X248451Y64483D03*
X248280Y78996D03*
X248451Y71078D03*
X248280Y94475D03*
Y101994D03*
Y86439D03*
X264861Y153964D03*
X253083D03*
X264861Y170131D03*
Y161692D03*
X253083Y170131D03*
Y161692D03*
X264596Y221664D03*
X252818D03*
X264596Y242684D03*
Y232179D03*
X252818Y242684D03*
Y232179D03*
X264596Y268188D03*
Y259749D03*
Y252021D03*
X252818Y268188D03*
Y252021D03*
Y259749D03*
X266040Y407146D03*
Y396631D03*
Y417651D03*
X257572Y396630D03*
Y407145D03*
X248714Y407536D03*
Y397021D03*
X257572Y417650D03*
X248714Y418041D03*
X248867Y482381D03*
X248696Y490299D03*
X248867Y468302D03*
Y475786D03*
X248696Y513297D03*
Y497742D03*
Y505778D03*
X267166Y581440D03*
Y572639D03*
Y609010D03*
Y601282D03*
Y591945D03*
X254710Y608108D03*
Y601513D03*
Y594029D03*
X247214Y608108D03*
Y601513D03*
Y594029D03*
X267166Y617449D03*
X254539Y631505D03*
Y623469D03*
Y616026D03*
X247043Y631505D03*
Y623469D03*
Y616026D03*
X267433Y624321D03*
X254539Y639024D03*
X247043D03*
X255021Y754782D03*
Y762510D03*
Y770949D03*
X263174Y855159D03*
Y862887D03*
X251396D03*
Y855159D03*
Y871326D03*
X263174D03*
X262766Y949344D03*
Y967106D03*
Y959859D03*
X262621Y974386D03*
X255086Y959673D03*
Y973752D03*
Y967157D03*
X247590Y959673D03*
Y973752D03*
Y967157D03*
X262621Y990553D03*
Y982114D03*
X254915Y981670D03*
Y997149D03*
Y989113D03*
X247419Y981670D03*
Y997149D03*
Y989113D03*
X254915Y1004668D03*
X247419D03*
X261219Y1124364D03*
Y1134879D03*
X251251Y1124364D03*
Y1134879D03*
X261219Y1145384D03*
X251251D03*
X254978Y1215296D03*
X247482D03*
X254978Y1207777D03*
Y1199741D03*
X247482Y1207777D03*
Y1199741D03*
X259581Y1272430D03*
Y1282945D03*
Y1293450D03*
Y1302787D03*
Y1310515D03*
Y1318954D03*
X263939Y1548010D03*
Y1534139D03*
Y1541055D03*
X261564Y1621823D03*
Y1642843D03*
Y1632338D03*
Y1668347D03*
Y1659908D03*
Y1652180D03*
X248878Y1670386D03*
X265759Y1697613D03*
X254718D03*
X265759Y1676593D03*
Y1687108D03*
X254718D03*
Y1676593D03*
X248707Y1699826D03*
X248878Y1677870D03*
Y1684465D03*
X248707Y1692383D03*
X254457Y1722140D03*
X265498D03*
X265759Y1714678D03*
X254718D03*
Y1706950D03*
X265759D03*
X248707Y1707862D03*
Y1715381D03*
X258639Y1819074D03*
Y1812119D03*
Y1805203D03*
X250468Y1819074D03*
Y1812119D03*
Y1805203D03*
X267396Y1819077D03*
Y1805206D03*
Y1812122D03*
X258459Y1826219D03*
X250288D03*
X267037Y1826222D03*
X258459Y1840090D03*
Y1833135D03*
X267037Y1833138D03*
Y1840093D03*
X250288Y1833135D03*
Y1840090D03*
X245582Y2031480D03*
Y2020965D03*
X258337D03*
Y2031480D03*
X245582Y2041985D03*
Y2051322D03*
Y2059050D03*
X258337Y2051322D03*
Y2059050D03*
Y2041985D03*
Y2067489D03*
X245582D03*
X288102Y54944D03*
Y45572D03*
X271572Y54944D03*
X279754D03*
X271572Y45572D03*
X279754D03*
X288102Y65449D03*
X271572D03*
X279754D03*
X274531Y407289D03*
Y396774D03*
Y417794D03*
X278944Y581440D03*
Y572639D03*
Y601282D03*
Y609010D03*
Y591945D03*
Y617449D03*
X279044Y624627D03*
X274544Y949344D03*
Y967106D03*
Y959859D03*
X274399Y974386D03*
Y990553D03*
Y982114D03*
X279015Y1124077D03*
X288363Y1123935D03*
X279015Y1134592D03*
X288363Y1134450D03*
X269975Y1134735D03*
Y1124220D03*
X288363Y1144955D03*
X279015Y1145097D03*
X269975Y1145240D03*
X286721Y1184312D03*
Y1192040D03*
X278182Y1184455D03*
Y1192183D03*
X286721Y1200479D03*
X278182Y1200622D03*
X270622Y1282945D03*
Y1272430D03*
Y1293450D03*
Y1302787D03*
Y1310515D03*
Y1318954D03*
X278400Y1548190D03*
X271534Y1548010D03*
X285995Y1548190D03*
X278400Y1534319D03*
Y1541235D03*
X271534Y1534139D03*
Y1541055D03*
X285995Y1534319D03*
Y1541235D03*
X273342Y1621823D03*
Y1642843D03*
Y1632338D03*
Y1668347D03*
Y1652180D03*
Y1659908D03*
X270115Y2031480D03*
Y2020965D03*
Y2051322D03*
Y2059050D03*
Y2041985D03*
Y2067489D03*
X300537Y516309D03*
X307966Y516419D03*
Y524147D03*
X300537Y524037D03*
Y532476D03*
X307966Y532586D03*
X292569Y524323D03*
Y516595D03*
Y532762D03*
X315187Y652457D03*
Y661258D03*
X304146D03*
Y652457D03*
Y681100D03*
X315187D03*
Y671763D03*
X304146D03*
X315187Y688828D03*
X304146D03*
Y697267D03*
X315187D03*
X307194Y1020657D03*
X307078Y1007303D03*
X307274Y1001286D03*
X307143Y1014094D03*
X307129Y1027081D03*
X306999Y1033718D03*
X303159Y1184526D03*
Y1192254D03*
X311936Y1192253D03*
Y1184525D03*
X294691Y1184526D03*
Y1192254D03*
X311936Y1200692D03*
X303159Y1200693D03*
X294691D03*
X309823Y1472957D03*
X309464Y1480102D03*
X309823Y1466002D03*
Y1459086D03*
X292715Y1480099D03*
X292895Y1472954D03*
X301066D03*
X300886Y1480099D03*
X292895Y1459083D03*
Y1465999D03*
X301066D03*
Y1459083D03*
X309464Y1493973D03*
Y1487018D03*
X292715Y1487015D03*
Y1493970D03*
X300886D03*
Y1487015D03*
X292754Y1917148D03*
X300349D03*
X292754Y1910232D03*
X300349D03*
X307215Y1910412D03*
X314810D03*
Y1917328D03*
X307215D03*
X292754Y1924103D03*
X300349D03*
X314810Y1924283D03*
X307215D03*
X332775Y318634D03*
X332693Y311980D03*
X332775Y335272D03*
Y342461D03*
Y325935D03*
X332685Y348655D03*
X325139Y516632D03*
Y524360D03*
X316791Y524432D03*
Y516704D03*
Y532871D03*
X325139Y532799D03*
X318235Y1020657D03*
X318315Y1001286D03*
X318119Y1007303D03*
X318184Y1014094D03*
X318170Y1027081D03*
X318040Y1033718D03*
X343816Y318634D03*
X343734Y311980D03*
X343816Y335272D03*
Y342461D03*
Y325935D03*
X343726Y348655D03*
X354391Y1329686D03*
Y1350706D03*
Y1360043D03*
Y1340201D03*
Y1376210D03*
Y1367771D03*
X366169Y1329686D03*
Y1350706D03*
Y1360043D03*
Y1340201D03*
Y1376210D03*
Y1367771D03*
G54D38*
G01X7673Y727049D02*
X10565Y728466D01*
X11236Y728241D01*
X11238Y728240D01*
X11461Y727795D01*
Y726228D01*
X10616Y725383D01*
Y720579D01*
X12765Y718430D01*
X16786D01*
X18925Y716291D01*
Y707635D01*
X27742Y698818D01*
Y695252D01*
X25755Y693265D01*
Y592475D01*
X25255Y591975D01*
X21646D01*
X20209Y590538D01*
Y586912D01*
X21646Y585475D01*
X25255D01*
X25755Y584975D01*
Y582675D01*
X25255Y582175D01*
X21646D01*
X20209Y580738D01*
Y577112D01*
X21646Y575675D01*
X25255D01*
X25755Y575175D01*
Y572875D01*
X25255Y572375D01*
X21646D01*
X20209Y570938D01*
Y567312D01*
X21646Y565875D01*
X25255D01*
X25755Y565375D01*
Y531037D01*
X17802Y523084D01*
Y515756D01*
X20008Y513549D01*
X20685Y513210D01*
X20690Y513207D01*
X20915Y512536D01*
X18995Y508701D01*
G01X15547Y730986D02*
X12893Y729626D01*
X12670Y728955D01*
X13061Y728173D01*
Y725565D01*
X12216Y724720D01*
Y721242D01*
X13428Y720030D01*
X17449D01*
X20525Y716954D01*
Y708298D01*
X29342Y699481D01*
Y694589D01*
X27355Y692602D01*
Y591812D01*
X25918Y590375D01*
X22309D01*
X21809Y589875D01*
Y587575D01*
X22309Y587075D01*
X25918D01*
X27355Y585638D01*
Y582012D01*
X25918Y580575D01*
X22309D01*
X21809Y580075D01*
Y577775D01*
X22309Y577275D01*
X25918D01*
X27355Y575838D01*
Y572212D01*
X25918Y570775D01*
X22309D01*
X21809Y570275D01*
Y567975D01*
X22309Y567475D01*
X25918D01*
X27355Y566038D01*
Y530374D01*
X19402Y522421D01*
Y516419D01*
X20956Y514864D01*
X21402Y514641D01*
X22073Y514864D01*
X23995Y518701D01*
G01X15547Y738860D02*
X12775Y740248D01*
X12104Y740023D01*
X11879Y739575D01*
X11878D01*
X11762Y739343D01*
X11578Y739159D01*
Y738167D01*
X14317Y735428D01*
X26991D01*
X31153Y739590D01*
X37823D01*
X43475Y733938D01*
Y620208D01*
X40960Y617693D01*
Y533102D01*
X49431Y524631D01*
Y516969D01*
X45303Y512841D01*
Y506312D01*
X41441Y502450D01*
X36074D01*
X33465Y505059D01*
Y512309D01*
X35008Y513853D01*
X35241Y513970D01*
X35685Y514192D01*
X35690Y514195D01*
X35915Y514866D01*
X33995Y518701D01*
G01X7673Y742797D02*
X10447Y741408D01*
X10670Y740737D01*
X10447Y740291D01*
X9978Y739822D01*
Y737504D01*
X13654Y733828D01*
X27654D01*
X31816Y737990D01*
X37160D01*
X41875Y733275D01*
Y655402D01*
X40827Y654354D01*
Y652854D01*
X41875Y651806D01*
Y650306D01*
X40827Y649258D01*
Y647758D01*
X41875Y646710D01*
Y645210D01*
X40827Y644162D01*
Y642662D01*
X41875Y641614D01*
Y640114D01*
X40827Y639066D01*
Y637566D01*
X41875Y636518D01*
Y635018D01*
X40827Y633970D01*
Y632470D01*
X41875Y631422D01*
Y629922D01*
X40827Y628874D01*
Y627374D01*
X41875Y626326D01*
Y620871D01*
X39360Y618356D01*
Y532439D01*
X47831Y523968D01*
Y517632D01*
X43703Y513504D01*
Y506975D01*
X40778Y504050D01*
X36737D01*
X35065Y505722D01*
Y511646D01*
X35957Y512539D01*
X35958D01*
X36402Y512761D01*
X37073Y512538D01*
X38995Y508701D01*
G01X23995Y1622992D02*
X22075Y1619157D01*
X21404Y1618934D01*
X20959Y1619157D01*
X20622Y1619325D01*
X14275D01*
X11482Y1616532D01*
Y1608321D01*
X25228Y1594575D01*
Y1564777D01*
X24464Y1564013D01*
Y1562513D01*
X25228Y1561749D01*
Y1560249D01*
X24464Y1559485D01*
Y1557985D01*
X25228Y1557221D01*
Y1556345D01*
X22291Y1553408D01*
Y1465001D01*
X20113Y1462823D01*
Y1379936D01*
X17877Y1377700D01*
X13629D01*
X11582Y1379747D01*
Y1380889D01*
X11766Y1381073D01*
X11882Y1381305D01*
X11883D01*
X12108Y1381753D01*
X12779Y1381978D01*
X15551Y1380590D01*
G01X7677Y1384527D02*
X10451Y1383138D01*
X10674Y1382467D01*
X10451Y1382021D01*
X9982Y1381552D01*
Y1379084D01*
X12966Y1376100D01*
X18540D01*
X21713Y1379273D01*
Y1462160D01*
X23891Y1464338D01*
Y1552745D01*
X26828Y1555682D01*
Y1595238D01*
X13082Y1608984D01*
Y1615869D01*
X14938Y1617725D01*
X20243D01*
X20687Y1617503D01*
X20692Y1617500D01*
X20917Y1616830D01*
X18995Y1612992D01*
G01X28995D02*
X32257D01*
X37555Y1607694D01*
Y1603803D01*
X39827Y1601531D01*
Y1599888D01*
X39175Y1599236D01*
Y1597736D01*
X39827Y1597084D01*
Y1595584D01*
X39175Y1594932D01*
Y1593432D01*
X39827Y1592780D01*
Y1591280D01*
X39175Y1590628D01*
Y1589128D01*
X39827Y1588476D01*
Y1586976D01*
X39175Y1586324D01*
Y1584824D01*
X39827Y1584172D01*
Y1582672D01*
X39175Y1582020D01*
Y1580520D01*
X39827Y1579868D01*
Y1578368D01*
X39175Y1577716D01*
Y1576216D01*
X39827Y1575564D01*
Y1574064D01*
X39175Y1573412D01*
Y1571912D01*
X39827Y1571260D01*
Y1569760D01*
X39175Y1569108D01*
Y1567608D01*
X39827Y1566956D01*
Y1565456D01*
X39175Y1564804D01*
Y1563304D01*
X39827Y1562652D01*
Y1561152D01*
X39175Y1560500D01*
Y1559000D01*
X39827Y1558348D01*
Y1556848D01*
X39175Y1556196D01*
Y1554696D01*
X39827Y1554044D01*
Y1552544D01*
X39175Y1551892D01*
Y1550392D01*
X39827Y1549740D01*
Y1548240D01*
X39175Y1547588D01*
Y1546088D01*
X39827Y1545436D01*
Y1543124D01*
X32808Y1536105D01*
Y1415550D01*
X36813Y1411545D01*
Y1408591D01*
X36087Y1407865D01*
Y1406365D01*
X36813Y1405639D01*
Y1404139D01*
X36087Y1403413D01*
Y1401913D01*
X36813Y1401187D01*
Y1399687D01*
X36087Y1398961D01*
Y1397461D01*
X36813Y1396735D01*
Y1395235D01*
X36087Y1394509D01*
Y1393009D01*
X36813Y1392283D01*
Y1390783D01*
X36087Y1390057D01*
Y1388557D01*
X36813Y1387831D01*
Y1375851D01*
X34351Y1373389D01*
X30347D01*
X26478Y1369520D01*
X13585D01*
X12664Y1370441D01*
X12556Y1370657D01*
X12779Y1371328D01*
X15551Y1372716D01*
G01X43995Y1622992D02*
Y1612657D01*
X39155Y1607817D01*
Y1604466D01*
X41427Y1602194D01*
Y1542461D01*
X34408Y1535442D01*
Y1416213D01*
X38413Y1412208D01*
Y1375188D01*
X35014Y1371789D01*
X31010D01*
X27141Y1367920D01*
X12922D01*
X11347Y1369495D01*
X11122Y1369943D01*
X10451Y1370168D01*
X7677Y1368779D01*
G01X25393Y1380590D02*
X27839D01*
X28672Y1381423D01*
Y1392736D01*
X27593Y1393815D01*
Y1550332D01*
X30788Y1553527D01*
Y1598968D01*
X23784Y1605972D01*
Y1615046D01*
X26844Y1618106D01*
X34971D01*
X35008Y1618144D01*
X35685Y1618483D01*
X35690Y1618486D01*
X35915Y1619157D01*
X33995Y1622992D01*
G01X33263Y727049D02*
X30489Y728438D01*
X30266Y729109D01*
X30489Y729555D01*
X31180Y730246D01*
X35501D01*
X36637Y729110D01*
Y690444D01*
X30932Y684739D01*
Y681372D01*
X32369Y679935D01*
X34383D01*
X34883Y679435D01*
Y677135D01*
X34383Y676635D01*
X32369D01*
X30932Y675198D01*
Y671572D01*
X32369Y670135D01*
X34383D01*
X34883Y669635D01*
Y667335D01*
X34383Y666835D01*
X32369D01*
X30932Y665398D01*
Y661772D01*
X32369Y660335D01*
X34383D01*
X34883Y659835D01*
Y657535D01*
X34383Y657035D01*
X32369D01*
X30932Y655598D01*
Y651972D01*
X32369Y650535D01*
X34383D01*
X34883Y650035D01*
Y647735D01*
X34383Y647235D01*
X32369D01*
X30932Y645798D01*
Y642172D01*
X32369Y640735D01*
X34383D01*
X34883Y640235D01*
Y637935D01*
X34383Y637435D01*
X32369D01*
X30932Y635998D01*
Y529501D01*
X33395Y527038D01*
Y526330D01*
X28995Y521930D01*
Y508701D01*
G01X25389Y738860D02*
X28163Y740249D01*
X28386Y740920D01*
X28163Y741366D01*
X27694Y741835D01*
Y744839D01*
X30166Y747311D01*
X39185D01*
X48638Y737858D01*
Y580148D01*
X46165Y577675D01*
Y574515D01*
X46665Y574015D01*
X48869D01*
X50306Y572578D01*
Y568952D01*
X48869Y567515D01*
X46665D01*
X46165Y567015D01*
Y556706D01*
X49121Y553750D01*
Y533344D01*
X59534Y522931D01*
Y515048D01*
X56556Y512070D01*
X52501D01*
X52033Y512538D01*
X51588Y512761D01*
X50917Y512538D01*
X48995Y508701D01*
G01X25389Y730986D02*
X28161Y729598D01*
X28832Y729823D01*
X29057Y730271D01*
X29058D01*
X29174Y730503D01*
X30517Y731846D01*
X36164D01*
X38237Y729773D01*
Y689781D01*
X32532Y684076D01*
Y682035D01*
X33032Y681535D01*
X35046D01*
X36483Y680098D01*
Y676472D01*
X35046Y675035D01*
X33032D01*
X32532Y674535D01*
Y672235D01*
X33032Y671735D01*
X35046D01*
X36483Y670298D01*
Y666672D01*
X35046Y665235D01*
X33032D01*
X32532Y664735D01*
Y662435D01*
X33032Y661935D01*
X35046D01*
X36483Y660498D01*
Y656872D01*
X35046Y655435D01*
X33032D01*
X32532Y654935D01*
Y652635D01*
X33032Y652135D01*
X35046D01*
X36483Y650698D01*
Y647072D01*
X35046Y645635D01*
X33032D01*
X32532Y645135D01*
Y642835D01*
X33032Y642335D01*
X35046D01*
X36483Y640898D01*
Y637272D01*
X35046Y635835D01*
X33032D01*
X32532Y635335D01*
Y551495D01*
X33287Y550741D01*
Y549241D01*
X32532Y548487D01*
Y546987D01*
X33287Y546233D01*
Y544733D01*
X32532Y543979D01*
Y542479D01*
X33287Y541725D01*
Y540225D01*
X32532Y539471D01*
Y537971D01*
X33287Y537217D01*
Y535717D01*
X32532Y534963D01*
Y530164D01*
X43995Y518701D01*
G01X33263Y742797D02*
X30491Y741409D01*
X29820Y741634D01*
X29595Y742082D01*
X29594D01*
X29478Y742314D01*
X29294Y742498D01*
Y744176D01*
X30829Y745711D01*
X38522D01*
X47038Y737195D01*
Y615177D01*
X46134Y614273D01*
Y612773D01*
X47038Y611869D01*
Y610369D01*
X46134Y609465D01*
Y607965D01*
X47038Y607061D01*
Y605561D01*
X46134Y604657D01*
Y603157D01*
X47038Y602253D01*
Y600753D01*
X46134Y599849D01*
Y598349D01*
X47038Y597445D01*
Y595945D01*
X46134Y595041D01*
Y593541D01*
X47038Y592637D01*
Y591137D01*
X46134Y590233D01*
Y588733D01*
X47038Y587829D01*
Y586329D01*
X46134Y585425D01*
Y583925D01*
X47038Y583021D01*
Y580811D01*
X44565Y578338D01*
Y573852D01*
X46002Y572415D01*
X48206D01*
X48706Y571915D01*
Y569615D01*
X48206Y569115D01*
X46002D01*
X44565Y567678D01*
Y556043D01*
X47521Y553087D01*
Y550353D01*
X46931Y549763D01*
Y548263D01*
X47521Y547673D01*
Y546173D01*
X46931Y545583D01*
Y544083D01*
X47521Y543493D01*
Y541993D01*
X46931Y541403D01*
Y539903D01*
X47521Y539313D01*
Y537813D01*
X46931Y537223D01*
Y535723D01*
X47521Y535133D01*
Y532681D01*
X49923Y530279D01*
Y529153D01*
X50984Y528092D01*
X52110D01*
X53171Y527031D01*
Y525905D01*
X54232Y524844D01*
X55358D01*
X57934Y522268D01*
Y515711D01*
X55893Y513670D01*
X53164D01*
X52982Y513853D01*
X52749Y513970D01*
X52305Y514192D01*
X52300Y514195D01*
X52075Y514866D01*
X53995Y518701D01*
G01X25393Y1364842D02*
X28129Y1366202D01*
X28800Y1365977D01*
X29025Y1365529D01*
X30195Y1364359D01*
X35248D01*
X43387Y1372498D01*
Y1455123D01*
X39496Y1459014D01*
Y1533162D01*
X47195Y1540861D01*
Y1591189D01*
X55843Y1599837D01*
Y1615282D01*
X52982Y1618144D01*
X52749Y1618261D01*
X52305Y1618483D01*
X52300Y1618486D01*
X52075Y1619157D01*
X53995Y1622992D01*
G01X33267Y1368779D02*
X30457Y1367362D01*
X30234Y1366691D01*
X30342Y1366475D01*
X30858Y1365959D01*
X34585D01*
X41787Y1373161D01*
Y1417425D01*
X40816Y1418395D01*
Y1419895D01*
X41787Y1420865D01*
Y1422365D01*
X40816Y1423335D01*
Y1424835D01*
X41787Y1425805D01*
Y1427305D01*
X40816Y1428275D01*
Y1429775D01*
X41787Y1430745D01*
Y1432245D01*
X40816Y1433215D01*
Y1434715D01*
X41787Y1435685D01*
Y1437185D01*
X40816Y1438155D01*
Y1439655D01*
X41787Y1440625D01*
Y1442125D01*
X40816Y1443095D01*
Y1444595D01*
X41787Y1445565D01*
Y1454460D01*
X37896Y1458351D01*
Y1533825D01*
X45595Y1541524D01*
Y1591852D01*
X54243Y1600500D01*
Y1614619D01*
X52033Y1616830D01*
X52032D01*
X51588Y1617052D01*
X50917Y1616829D01*
X48995Y1612992D01*
G01X33267Y1376653D02*
X30272Y1379648D01*
Y1393399D01*
X29193Y1394478D01*
Y1549669D01*
X32388Y1552864D01*
Y1599631D01*
X25384Y1606635D01*
Y1614383D01*
X27507Y1616506D01*
X35634D01*
X35957Y1616829D01*
X36402Y1617052D01*
X37073Y1616829D01*
X38995Y1612992D01*
G54D29*
X119920Y18071D03*
Y28071D03*
Y38071D03*
Y48071D03*
Y58071D03*
Y68071D03*
Y78071D03*
Y88071D03*
Y98071D03*
Y108071D03*
Y118071D03*
Y128071D03*
Y138071D03*
Y148071D03*
Y158071D03*
Y168071D03*
Y178071D03*
Y188071D03*
Y198071D03*
Y208071D03*
Y218071D03*
Y228071D03*
Y238071D03*
Y248071D03*
Y258071D03*
Y268071D03*
Y278071D03*
Y288071D03*
Y298071D03*
Y308071D03*
Y318071D03*
Y366102D03*
Y376102D03*
Y386102D03*
Y396102D03*
Y406102D03*
Y416102D03*
Y426102D03*
Y436102D03*
Y446102D03*
Y456102D03*
Y466102D03*
Y476102D03*
Y486102D03*
Y496102D03*
Y506102D03*
Y516102D03*
Y526102D03*
Y536102D03*
Y546102D03*
Y556102D03*
Y566102D03*
Y576102D03*
Y586102D03*
Y596102D03*
Y606102D03*
Y616102D03*
Y626102D03*
Y636102D03*
Y646102D03*
Y656102D03*
Y666102D03*
Y714134D03*
Y724134D03*
Y734134D03*
Y744134D03*
Y754134D03*
Y764134D03*
Y774134D03*
Y784134D03*
Y794134D03*
Y804134D03*
Y814134D03*
Y824134D03*
Y834134D03*
Y844134D03*
Y854134D03*
Y864134D03*
Y874134D03*
Y884134D03*
Y894134D03*
Y904134D03*
Y914134D03*
Y924134D03*
Y934134D03*
Y944134D03*
Y954134D03*
Y964134D03*
Y974134D03*
Y984134D03*
Y994134D03*
Y1004134D03*
Y1014134D03*
Y1062165D03*
Y1072165D03*
Y1082165D03*
Y1092165D03*
Y1102165D03*
Y1112165D03*
Y1122165D03*
Y1132165D03*
Y1142165D03*
Y1152165D03*
Y1162165D03*
Y1172165D03*
Y1182165D03*
Y1192165D03*
Y1202165D03*
Y1212165D03*
Y1222165D03*
Y1232165D03*
Y1242165D03*
Y1252165D03*
Y1262165D03*
Y1272165D03*
Y1282165D03*
Y1292165D03*
Y1302165D03*
Y1312165D03*
Y1322165D03*
Y1332165D03*
Y1342165D03*
Y1352165D03*
Y1362165D03*
Y1410197D03*
Y1420197D03*
Y1430197D03*
Y1440197D03*
Y1450197D03*
Y1460197D03*
Y1470197D03*
Y1480197D03*
Y1490197D03*
Y1500197D03*
Y1510197D03*
Y1520197D03*
Y1530197D03*
Y1540197D03*
Y1550197D03*
Y1560197D03*
Y1570197D03*
Y1580197D03*
Y1590197D03*
Y1600197D03*
Y1610197D03*
Y1620197D03*
Y1630197D03*
Y1640197D03*
Y1650197D03*
Y1660197D03*
Y1670197D03*
Y1680197D03*
Y1690197D03*
Y1700197D03*
Y1710197D03*
Y1758228D03*
Y1768228D03*
Y1778228D03*
Y1788228D03*
Y1798228D03*
Y1808228D03*
Y1818228D03*
Y1828228D03*
Y1838228D03*
Y1848228D03*
Y1858228D03*
Y1868228D03*
Y1878228D03*
Y1888228D03*
Y1898228D03*
Y1908228D03*
Y1918228D03*
Y1928228D03*
Y1938228D03*
Y1948228D03*
Y1958228D03*
Y1968228D03*
Y1978228D03*
Y1988228D03*
Y1998228D03*
Y2008228D03*
Y2018228D03*
Y2028228D03*
Y2038228D03*
Y2048228D03*
Y2058228D03*
X139920Y28071D03*
Y18071D03*
Y58071D03*
Y48071D03*
Y38071D03*
Y78071D03*
Y68071D03*
Y98071D03*
Y88071D03*
Y128071D03*
Y118071D03*
Y108071D03*
Y148071D03*
Y138071D03*
Y178071D03*
Y168071D03*
Y158071D03*
Y198071D03*
Y188071D03*
Y228071D03*
Y218071D03*
Y208071D03*
Y248071D03*
Y238071D03*
Y268071D03*
Y258071D03*
Y298071D03*
Y288071D03*
Y278071D03*
Y318071D03*
Y308071D03*
Y328071D03*
Y366102D03*
Y396102D03*
Y386102D03*
Y376102D03*
Y416102D03*
Y406102D03*
Y436102D03*
Y426102D03*
Y466102D03*
Y456102D03*
Y446102D03*
Y486102D03*
Y476102D03*
Y516102D03*
Y506102D03*
Y496102D03*
Y536102D03*
Y526102D03*
Y566102D03*
Y556102D03*
Y546102D03*
Y586102D03*
Y576102D03*
Y606102D03*
Y596102D03*
Y636102D03*
Y626102D03*
Y616102D03*
Y656102D03*
Y646102D03*
Y676102D03*
Y666102D03*
Y734134D03*
Y724134D03*
Y714134D03*
Y754134D03*
Y744134D03*
Y774134D03*
Y764134D03*
Y804134D03*
Y794134D03*
Y784134D03*
Y824134D03*
Y814134D03*
Y854134D03*
Y844134D03*
Y834134D03*
Y874134D03*
Y864134D03*
Y904134D03*
Y894134D03*
Y884134D03*
Y924134D03*
Y914134D03*
Y944134D03*
Y934134D03*
Y974134D03*
Y964134D03*
Y954134D03*
Y994134D03*
Y984134D03*
Y1024134D03*
Y1014134D03*
Y1004134D03*
Y1072165D03*
Y1062165D03*
Y1092165D03*
Y1082165D03*
Y1122165D03*
Y1112165D03*
Y1102165D03*
Y1142165D03*
Y1132165D03*
Y1162165D03*
Y1152165D03*
Y1192165D03*
Y1182165D03*
Y1172165D03*
Y1212165D03*
Y1202165D03*
Y1242165D03*
Y1232165D03*
Y1222165D03*
Y1262165D03*
Y1252165D03*
Y1282165D03*
Y1272165D03*
Y1312165D03*
Y1302165D03*
Y1292165D03*
Y1332165D03*
Y1322165D03*
Y1362165D03*
Y1352165D03*
Y1342165D03*
Y1372165D03*
Y1410197D03*
Y1430197D03*
Y1420197D03*
Y1460197D03*
Y1450197D03*
Y1440197D03*
Y1480197D03*
Y1470197D03*
Y1500197D03*
Y1490197D03*
Y1530197D03*
Y1520197D03*
Y1510197D03*
Y1550197D03*
Y1540197D03*
Y1580197D03*
Y1570197D03*
Y1560197D03*
Y1600197D03*
Y1590197D03*
Y1620197D03*
Y1610197D03*
Y1650197D03*
Y1640197D03*
Y1630197D03*
Y1670197D03*
Y1660197D03*
Y1700197D03*
Y1690197D03*
Y1680197D03*
Y1720197D03*
Y1710197D03*
Y1768228D03*
Y1758228D03*
Y1798228D03*
Y1788228D03*
Y1778228D03*
Y1818228D03*
Y1808228D03*
Y1838228D03*
Y1828228D03*
Y1868228D03*
Y1858228D03*
Y1848228D03*
Y1888228D03*
Y1878228D03*
Y1918228D03*
Y1908228D03*
Y1898228D03*
Y1938228D03*
Y1928228D03*
Y1958228D03*
Y1948228D03*
Y1988228D03*
Y1978228D03*
Y1968228D03*
Y2008228D03*
Y1998228D03*
Y2038228D03*
Y2028228D03*
Y2018228D03*
Y2058228D03*
Y2048228D03*
Y2068228D03*
G54D39*
G01X-723776Y2987387D02*
Y-376795D01*
Y-489221D01*
X1782976D01*
Y-376795D01*
Y2987387D01*
X-723776D01*
G01X-4000Y-62500D02*
Y-137500D01*
X496000D01*
Y-62500D01*
X-4000D01*
G01X8000Y-127500D02*
Y-132500D01*
G01X6543Y-127500D02*
X9457D01*
G01X14367Y-132500D02*
X11833D01*
Y-127500D01*
X14367D01*
G01X13353Y-129917D02*
X11833D01*
G01X16933Y-127500D02*
Y-132500D01*
X19467D01*
G01X23300Y-132667D02*
X23173Y-132583D01*
Y-132417D01*
X23300Y-132333D01*
X23427Y-132417D01*
Y-132583D01*
X23300Y-132667D01*
G01Y-130417D02*
X23173Y-130333D01*
Y-130167D01*
X23300Y-130083D01*
X23427Y-130167D01*
Y-130333D01*
X23300Y-130417D01*
G01X28083Y-134167D02*
X27450Y-133333D01*
X27133Y-132500D01*
Y-129167D01*
X27450Y-128333D01*
X28083Y-127500D01*
G01X33500D02*
X32993Y-127667D01*
X32613Y-128083D01*
X32360Y-128583D01*
X32170Y-129250D01*
X32107Y-130000D01*
X32170Y-130750D01*
X32360Y-131417D01*
X32613Y-131917D01*
X32993Y-132333D01*
X33500Y-132500D01*
X34007Y-132333D01*
X34387Y-131917D01*
X34640Y-131417D01*
X34830Y-130750D01*
X34893Y-130000D01*
X34830Y-129250D01*
X34640Y-128583D01*
X34387Y-128083D01*
X34007Y-127667D01*
X33500Y-127500D01*
G01X37207Y-131500D02*
X37587Y-132083D01*
X38093Y-132417D01*
X38663Y-132500D01*
X39170Y-132417D01*
X39677Y-132000D01*
X39993Y-131500D01*
X40057Y-131000D01*
X39930Y-130417D01*
X39487Y-130000D01*
X39043Y-129833D01*
X38473D01*
G01X39043D02*
X39423Y-129583D01*
X39740Y-129167D01*
X39867Y-128667D01*
X39740Y-128167D01*
X39423Y-127750D01*
X38853Y-127500D01*
X38283Y-127583D01*
X37713Y-127917D01*
G01X44017Y-134167D02*
X44650Y-133333D01*
X44967Y-132500D01*
Y-129167D01*
X44650Y-128333D01*
X44017Y-127500D01*
G01X47407Y-131500D02*
X47787Y-132083D01*
X48293Y-132417D01*
X48863Y-132500D01*
X49370Y-132417D01*
X49877Y-132000D01*
X50193Y-131500D01*
X50257Y-131000D01*
X50130Y-130417D01*
X49687Y-130000D01*
X49243Y-129833D01*
X48673D01*
G01X49243D02*
X49623Y-129583D01*
X49940Y-129167D01*
X50067Y-128667D01*
X49940Y-128167D01*
X49623Y-127750D01*
X49053Y-127500D01*
X48483Y-127583D01*
X47913Y-127917D01*
G01X52697Y-128333D02*
X53077Y-127833D01*
X53520Y-127583D01*
X54027Y-127500D01*
X54660Y-127667D01*
X55103Y-128083D01*
X55230Y-128583D01*
X55167Y-129083D01*
X54913Y-129500D01*
X53647Y-130333D01*
X53077Y-130917D01*
X52697Y-131750D01*
X52570Y-132500D01*
X55230D01*
G01X58873D02*
X59000Y-131417D01*
X59190Y-130500D01*
X59443Y-129667D01*
X59760Y-128750D01*
X60267Y-127500D01*
X57733D01*
G01X63277Y-130833D02*
X64923D01*
G01X67997Y-128333D02*
X68377Y-127833D01*
X68820Y-127583D01*
X69327Y-127500D01*
X69960Y-127667D01*
X70403Y-128083D01*
X70530Y-128583D01*
X70467Y-129083D01*
X70213Y-129500D01*
X68947Y-130333D01*
X68377Y-130917D01*
X67997Y-131750D01*
X67870Y-132500D01*
X70530D01*
G01X72907Y-131500D02*
X73287Y-132083D01*
X73793Y-132417D01*
X74363Y-132500D01*
X74870Y-132417D01*
X75377Y-132000D01*
X75693Y-131500D01*
X75757Y-131000D01*
X75630Y-130417D01*
X75187Y-130000D01*
X74743Y-129833D01*
X74173D01*
G01X74743D02*
X75123Y-129583D01*
X75440Y-129167D01*
X75567Y-128667D01*
X75440Y-128167D01*
X75123Y-127750D01*
X74553Y-127500D01*
X73983Y-127583D01*
X73413Y-127917D01*
G01X80160Y-132500D02*
Y-127500D01*
X77817Y-131083D01*
X80983D01*
G01X83107Y-131750D02*
X83487Y-132167D01*
X83930Y-132417D01*
X84500Y-132500D01*
X85070Y-132333D01*
X85513Y-132000D01*
X85830Y-131417D01*
X85893Y-130750D01*
X85767Y-130083D01*
X85450Y-129667D01*
X85007Y-129333D01*
X84563Y-129250D01*
X84120Y-129333D01*
X83550Y-129667D01*
X83740Y-127500D01*
X85450D01*
G01X93497Y-132500D02*
Y-127500D01*
X95903D01*
G01X95017Y-129917D02*
X93497D01*
G01X98217Y-132500D02*
X99800Y-127500D01*
X101383Y-132500D01*
G01X100813Y-130750D02*
X98787D01*
G01X103570Y-132500D02*
X106230Y-127500D01*
G01X103570D02*
X106230Y-132500D01*
G01X110000Y-132667D02*
X109873Y-132583D01*
Y-132417D01*
X110000Y-132333D01*
X110127Y-132417D01*
Y-132583D01*
X110000Y-132667D01*
G01Y-130417D02*
X109873Y-130333D01*
Y-130167D01*
X110000Y-130083D01*
X110127Y-130167D01*
Y-130333D01*
X110000Y-130417D01*
G01X114783Y-134167D02*
X114150Y-133333D01*
X113833Y-132500D01*
Y-129167D01*
X114150Y-128333D01*
X114783Y-127500D01*
G01X120200D02*
X119693Y-127667D01*
X119313Y-128083D01*
X119060Y-128583D01*
X118870Y-129250D01*
X118807Y-130000D01*
X118870Y-130750D01*
X119060Y-131417D01*
X119313Y-131917D01*
X119693Y-132333D01*
X120200Y-132500D01*
X120707Y-132333D01*
X121087Y-131917D01*
X121340Y-131417D01*
X121530Y-130750D01*
X121593Y-130000D01*
X121530Y-129250D01*
X121340Y-128583D01*
X121087Y-128083D01*
X120707Y-127667D01*
X120200Y-127500D01*
G01X123907Y-131500D02*
X124287Y-132083D01*
X124793Y-132417D01*
X125363Y-132500D01*
X125870Y-132417D01*
X126377Y-132000D01*
X126693Y-131500D01*
X126757Y-131000D01*
X126630Y-130417D01*
X126187Y-130000D01*
X125743Y-129833D01*
X125173D01*
G01X125743D02*
X126123Y-129583D01*
X126440Y-129167D01*
X126567Y-128667D01*
X126440Y-128167D01*
X126123Y-127750D01*
X125553Y-127500D01*
X124983Y-127583D01*
X124413Y-127917D01*
G01X130717Y-134167D02*
X131350Y-133333D01*
X131667Y-132500D01*
Y-129167D01*
X131350Y-128333D01*
X130717Y-127500D01*
G01X134107Y-131500D02*
X134487Y-132083D01*
X134993Y-132417D01*
X135563Y-132500D01*
X136070Y-132417D01*
X136577Y-132000D01*
X136893Y-131500D01*
X136957Y-131000D01*
X136830Y-130417D01*
X136387Y-130000D01*
X135943Y-129833D01*
X135373D01*
G01X135943D02*
X136323Y-129583D01*
X136640Y-129167D01*
X136767Y-128667D01*
X136640Y-128167D01*
X136323Y-127750D01*
X135753Y-127500D01*
X135183Y-127583D01*
X134613Y-127917D01*
G01X139523Y-131917D02*
X139967Y-132333D01*
X140473Y-132500D01*
X140980Y-132333D01*
X141423Y-131833D01*
X141740Y-131083D01*
X141867Y-130333D01*
Y-129417D01*
X141740Y-128667D01*
X141423Y-128000D01*
X141043Y-127667D01*
X140600Y-127500D01*
X140093Y-127667D01*
X139713Y-128000D01*
X139460Y-128500D01*
X139333Y-129167D01*
X139460Y-129750D01*
X139777Y-130333D01*
X140157Y-130667D01*
X140600Y-130750D01*
X141107Y-130583D01*
X141487Y-130167D01*
X141867Y-129417D01*
G01X145573Y-132500D02*
X145700Y-131417D01*
X145890Y-130500D01*
X146143Y-129667D01*
X146460Y-128750D01*
X146967Y-127500D01*
X144433D01*
G01X149977Y-130833D02*
X151623D01*
G01X154507Y-131500D02*
X154887Y-132083D01*
X155393Y-132417D01*
X155963Y-132500D01*
X156470Y-132417D01*
X156977Y-132000D01*
X157293Y-131500D01*
X157357Y-131000D01*
X157230Y-130417D01*
X156787Y-130000D01*
X156343Y-129833D01*
X155773D01*
G01X156343D02*
X156723Y-129583D01*
X157040Y-129167D01*
X157167Y-128667D01*
X157040Y-128167D01*
X156723Y-127750D01*
X156153Y-127500D01*
X155583Y-127583D01*
X155013Y-127917D01*
G01X159797Y-130417D02*
X160240Y-129833D01*
X160620Y-129500D01*
X161127Y-129333D01*
X161570Y-129500D01*
X161887Y-129833D01*
X162140Y-130333D01*
X162203Y-130917D01*
X162140Y-131417D01*
X161887Y-131917D01*
X161507Y-132333D01*
X161063Y-132500D01*
X160557Y-132333D01*
X160113Y-131833D01*
X159860Y-131083D01*
X159797Y-130250D01*
X159923Y-129167D01*
X160113Y-128583D01*
X160430Y-128000D01*
X160873Y-127583D01*
X161317Y-127500D01*
X161760Y-127667D01*
X162077Y-128083D01*
G01X166100Y-132500D02*
Y-127500D01*
X165340Y-128500D01*
G01Y-132500D02*
X166860D01*
G01X171960D02*
Y-127500D01*
X169617Y-131083D01*
X172783D01*
G01X191000Y-62500D02*
Y-137500D01*
G01Y-112500D02*
X294000D01*
Y-87500D01*
G01X191000D02*
X294000D01*
G01X301507Y-122500D02*
Y-117500D01*
X302773D01*
X303280Y-117750D01*
X303660Y-118083D01*
X303977Y-118583D01*
X304230Y-119167D01*
X304293Y-120000D01*
X304230Y-120833D01*
X303977Y-121417D01*
X303660Y-121917D01*
X303280Y-122250D01*
X302773Y-122500D01*
X301507D01*
G01X306417D02*
X308000Y-117500D01*
X309583Y-122500D01*
G01X309013Y-120750D02*
X306987D01*
G01X313100Y-117500D02*
Y-122500D01*
G01X311643Y-117500D02*
X314557D01*
G01X319467Y-122500D02*
X316933D01*
Y-117500D01*
X319467D01*
G01X318453Y-119917D02*
X316933D01*
G01X323300Y-122667D02*
X323173Y-122583D01*
Y-122417D01*
X323300Y-122333D01*
X323427Y-122417D01*
Y-122583D01*
X323300Y-122667D01*
G01Y-120417D02*
X323173Y-120333D01*
Y-120167D01*
X323300Y-120083D01*
X323427Y-120167D01*
Y-120333D01*
X323300Y-120417D01*
G01X296000Y-62500D02*
Y-137500D01*
G01X294000Y-62500D02*
Y-137500D01*
G01X301633Y-97500D02*
Y-92500D01*
X303153D01*
X303660Y-92750D01*
X304040Y-93333D01*
X304167Y-94000D01*
X304040Y-94667D01*
X303723Y-95167D01*
X303153Y-95417D01*
X301633D01*
G01X306860Y-97667D02*
X309140Y-92500D01*
G01X311643Y-97500D02*
Y-92500D01*
X314557Y-97500D01*
Y-92500D01*
G01X318200Y-97667D02*
X318073Y-97583D01*
Y-97417D01*
X318200Y-97333D01*
X318327Y-97417D01*
Y-97583D01*
X318200Y-97667D01*
G01Y-95417D02*
X318073Y-95333D01*
Y-95167D01*
X318200Y-95083D01*
X318327Y-95167D01*
Y-95333D01*
X318200Y-95417D01*
G01X296000Y-112500D02*
X496000D01*
G01X301633Y-72500D02*
Y-67500D01*
X303153D01*
X303660Y-67750D01*
X304040Y-68333D01*
X304167Y-69000D01*
X304040Y-69667D01*
X303723Y-70167D01*
X303153Y-70417D01*
X301633D01*
G01X306733Y-72500D02*
Y-67500D01*
X308317D01*
X308823Y-67750D01*
X309140Y-68083D01*
X309267Y-68750D01*
X309140Y-69417D01*
X308760Y-69833D01*
X308317Y-70083D01*
X306733D01*
G01X308317D02*
X309267Y-72500D01*
G01X313100D02*
X312593Y-72417D01*
X312150Y-72083D01*
X311770Y-71583D01*
X311517Y-71000D01*
X311390Y-70333D01*
Y-69667D01*
X311517Y-69000D01*
X311770Y-68417D01*
X312150Y-67917D01*
X312593Y-67583D01*
X313100Y-67500D01*
X313607Y-67583D01*
X314050Y-67917D01*
X314430Y-68417D01*
X314683Y-69000D01*
X314810Y-69667D01*
Y-70333D01*
X314683Y-71000D01*
X314430Y-71583D01*
X314050Y-72083D01*
X313607Y-72417D01*
X313100Y-72500D01*
G01X316933Y-71500D02*
X317250Y-72000D01*
X317630Y-72333D01*
X318073Y-72500D01*
X318580Y-72333D01*
X318960Y-72000D01*
X319340Y-71500D01*
X319467Y-70833D01*
Y-67500D01*
G01X324567Y-72500D02*
X322033D01*
Y-67500D01*
X324567D01*
G01X323553Y-69917D02*
X322033D01*
G01X329793Y-67917D02*
X329413Y-67667D01*
X328970Y-67500D01*
X328463D01*
X327893Y-67750D01*
X327450Y-68167D01*
X327133Y-68667D01*
X326880Y-69500D01*
X326817Y-70250D01*
X326943Y-71000D01*
X327133Y-71500D01*
X327513Y-72000D01*
X327957Y-72333D01*
X328400Y-72500D01*
X328843D01*
X329287Y-72333D01*
X329667Y-72083D01*
X329983Y-71750D01*
G01X333500Y-67500D02*
Y-72500D01*
G01X332043Y-67500D02*
X334957D01*
G01X338600Y-72667D02*
X338473Y-72583D01*
Y-72417D01*
X338600Y-72333D01*
X338727Y-72417D01*
Y-72583D01*
X338600Y-72667D01*
G01Y-70417D02*
X338473Y-70333D01*
Y-70167D01*
X338600Y-70083D01*
X338727Y-70167D01*
Y-70333D01*
X338600Y-70417D01*
G01X296000Y-87500D02*
X496000D01*
G01X411000Y-112500D02*
Y-137500D01*
G01X416633Y-122500D02*
Y-117500D01*
X418217D01*
X418723Y-117750D01*
X419040Y-118083D01*
X419167Y-118750D01*
X419040Y-119417D01*
X418660Y-119833D01*
X418217Y-120083D01*
X416633D01*
G01X418217D02*
X419167Y-122500D01*
G01X424267D02*
X421733D01*
Y-117500D01*
X424267D01*
G01X423253Y-119917D02*
X421733D01*
G01X426517Y-117500D02*
X428100Y-122500D01*
X429683Y-117500D01*
G01X433200Y-122667D02*
X433073Y-122583D01*
Y-122417D01*
X433200Y-122333D01*
X433327Y-122417D01*
Y-122583D01*
X433200Y-122667D01*
G01Y-120417D02*
X433073Y-120333D01*
Y-120167D01*
X433200Y-120083D01*
X433327Y-120167D01*
Y-120333D01*
X433200Y-120417D01*
G01X460000Y-112500D02*
Y-137500D01*
G01X-723776Y2987387D02*
Y-376795D01*
Y-489221D01*
X1782976D01*
Y-376795D01*
Y2987387D01*
X-723776D01*
G01X6705Y-124160D02*
X7332Y-124685D01*
X8037Y-125000D01*
X8663D01*
X9290Y-124685D01*
X9760Y-124160D01*
X9995Y-123425D01*
X9838Y-122690D01*
X9447Y-122060D01*
X8742Y-121640D01*
X7802Y-121430D01*
X7253Y-121010D01*
X7018Y-120275D01*
X7175Y-119540D01*
X7567Y-119015D01*
X8115Y-118700D01*
X8663D01*
X9212Y-118910D01*
X9682Y-119435D01*
G01X13005Y-125000D02*
Y-118700D01*
G01X16295D02*
Y-125000D01*
G01Y-121850D02*
X13005D01*
G01X20010Y-118700D02*
X21890D01*
G01X20950D02*
Y-125000D01*
G01X20010D02*
X21890D01*
G01X28817D02*
X25683D01*
Y-118700D01*
X28817D01*
G01X27563Y-121745D02*
X25683D01*
G01X31748Y-125000D02*
Y-118700D01*
X35352Y-125000D01*
Y-118700D01*
G01X39693Y-126155D02*
X40007Y-124790D01*
G01X46150Y-118700D02*
Y-125000D01*
G01X44348Y-118700D02*
X47952D01*
G01X50492Y-125000D02*
X52450Y-118700D01*
X54408Y-125000D01*
G01X53703Y-122795D02*
X51197D01*
G01X57810Y-118700D02*
X59690D01*
G01X58750D02*
Y-125000D01*
G01X57810D02*
X59690D01*
G01X62700Y-118700D02*
X63797Y-125000D01*
X65050Y-118700D01*
X66303Y-125000D01*
X67400Y-118700D01*
G01X69392Y-125000D02*
X71350Y-118700D01*
X73308Y-125000D01*
G01X72603Y-122795D02*
X70097D01*
G01X75848Y-125000D02*
Y-118700D01*
X79452Y-125000D01*
Y-118700D01*
G01X88683Y-125000D02*
Y-118700D01*
X90642D01*
X91268Y-119015D01*
X91660Y-119435D01*
X91817Y-120275D01*
X91660Y-121115D01*
X91190Y-121640D01*
X90642Y-121955D01*
X88683D01*
G01X90642D02*
X91817Y-125000D01*
G01X96550Y-125210D02*
X96393Y-125105D01*
Y-124895D01*
X96550Y-124790D01*
X96707Y-124895D01*
Y-125105D01*
X96550Y-125210D01*
G01X102850Y-125000D02*
X102223Y-124895D01*
X101675Y-124475D01*
X101205Y-123845D01*
X100892Y-123110D01*
X100735Y-122270D01*
Y-121430D01*
X100892Y-120590D01*
X101205Y-119855D01*
X101675Y-119225D01*
X102223Y-118805D01*
X102850Y-118700D01*
X103477Y-118805D01*
X104025Y-119225D01*
X104495Y-119855D01*
X104808Y-120590D01*
X104965Y-121430D01*
Y-122270D01*
X104808Y-123110D01*
X104495Y-123845D01*
X104025Y-124475D01*
X103477Y-124895D01*
X102850Y-125000D01*
G01X109150Y-125210D02*
X108993Y-125105D01*
Y-124895D01*
X109150Y-124790D01*
X109307Y-124895D01*
Y-125105D01*
X109150Y-125210D01*
G01X117173Y-119225D02*
X116703Y-118910D01*
X116155Y-118700D01*
X115528D01*
X114823Y-119015D01*
X114275Y-119540D01*
X113883Y-120170D01*
X113570Y-121220D01*
X113492Y-122165D01*
X113648Y-123110D01*
X113883Y-123740D01*
X114353Y-124370D01*
X114902Y-124790D01*
X115450Y-125000D01*
X115998D01*
X116547Y-124790D01*
X117017Y-124475D01*
X117408Y-124055D01*
G01X121750Y-125210D02*
X121593Y-125105D01*
Y-124895D01*
X121750Y-124790D01*
X121907Y-124895D01*
Y-125105D01*
X121750Y-125210D01*
G01X6627Y-115000D02*
Y-108700D01*
G01X9603D02*
X6627Y-112585D01*
G01X10073Y-115000D02*
X7958Y-110800D01*
G01X12927Y-108700D02*
Y-113215D01*
X13240Y-114160D01*
X13867Y-114790D01*
X14650Y-115000D01*
X15433Y-114790D01*
X16060Y-114160D01*
X16373Y-113215D01*
Y-108700D01*
G01X22517Y-115000D02*
X19383D01*
Y-108700D01*
X22517D01*
G01X21263Y-111745D02*
X19383D01*
G01X26310Y-108700D02*
X28190D01*
G01X27250D02*
Y-115000D01*
G01X26310D02*
X28190D01*
G01X38205Y-114160D02*
X38832Y-114685D01*
X39537Y-115000D01*
X40163D01*
X40790Y-114685D01*
X41260Y-114160D01*
X41495Y-113425D01*
X41338Y-112690D01*
X40947Y-112060D01*
X40242Y-111640D01*
X39302Y-111430D01*
X38753Y-111010D01*
X38518Y-110275D01*
X38675Y-109540D01*
X39067Y-109015D01*
X39615Y-108700D01*
X40163D01*
X40712Y-108910D01*
X41182Y-109435D01*
G01X44505Y-115000D02*
Y-108700D01*
G01X47795D02*
Y-115000D01*
G01Y-111850D02*
X44505D01*
G01X50492Y-115000D02*
X52450Y-108700D01*
X54408Y-115000D01*
G01X53703Y-112795D02*
X51197D01*
G01X56948Y-115000D02*
Y-108700D01*
X60552Y-115000D01*
Y-108700D01*
G01X69705Y-115000D02*
Y-108700D01*
G01X72995D02*
Y-115000D01*
G01Y-111850D02*
X69705D01*
G01X76005Y-114160D02*
X76632Y-114685D01*
X77337Y-115000D01*
X77963D01*
X78590Y-114685D01*
X79060Y-114160D01*
X79295Y-113425D01*
X79138Y-112690D01*
X78747Y-112060D01*
X78042Y-111640D01*
X77102Y-111430D01*
X76553Y-111010D01*
X76318Y-110275D01*
X76475Y-109540D01*
X76867Y-109015D01*
X77415Y-108700D01*
X77963D01*
X78512Y-108910D01*
X78982Y-109435D01*
G01X83010Y-108700D02*
X84890D01*
G01X83950D02*
Y-115000D01*
G01X83010D02*
X84890D01*
G01X88292D02*
X90250Y-108700D01*
X92208Y-115000D01*
G01X91503Y-112795D02*
X88997D01*
G01X94748Y-115000D02*
Y-108700D01*
X98352Y-115000D01*
Y-108700D01*
G01X103320Y-111850D02*
X104887D01*
Y-113740D01*
X104417Y-114370D01*
X103868Y-114790D01*
X103085Y-115000D01*
X102302Y-114790D01*
X101753Y-114370D01*
X101283Y-113740D01*
X100970Y-113005D01*
X100813Y-112165D01*
Y-111430D01*
X100970Y-110800D01*
X101283Y-110065D01*
X101753Y-109435D01*
X102223Y-109015D01*
X102850Y-108700D01*
X103398D01*
X104025Y-108910D01*
X104495Y-109330D01*
G01X108993Y-116155D02*
X109307Y-114790D01*
G01X115450Y-108700D02*
Y-115000D01*
G01X113648Y-108700D02*
X117252D01*
G01X119792Y-115000D02*
X121750Y-108700D01*
X123708Y-115000D01*
G01X123003Y-112795D02*
X120497D01*
G01X128050Y-115000D02*
X127423Y-114895D01*
X126875Y-114475D01*
X126405Y-113845D01*
X126092Y-113110D01*
X125935Y-112270D01*
Y-111430D01*
X126092Y-110590D01*
X126405Y-109855D01*
X126875Y-109225D01*
X127423Y-108805D01*
X128050Y-108700D01*
X128677Y-108805D01*
X129225Y-109225D01*
X129695Y-109855D01*
X130008Y-110590D01*
X130165Y-111430D01*
Y-112270D01*
X130008Y-113110D01*
X129695Y-113845D01*
X129225Y-114475D01*
X128677Y-114895D01*
X128050Y-115000D01*
G01X140650D02*
Y-112165D01*
X139083Y-108700D01*
G01X142217D02*
X140650Y-112165D01*
G01X145227Y-108700D02*
Y-113215D01*
X145540Y-114160D01*
X146167Y-114790D01*
X146950Y-115000D01*
X147733Y-114790D01*
X148360Y-114160D01*
X148673Y-113215D01*
Y-108700D01*
G01X151292Y-115000D02*
X153250Y-108700D01*
X155208Y-115000D01*
G01X154503Y-112795D02*
X151997D01*
G01X157748Y-115000D02*
Y-108700D01*
X161352Y-115000D01*
Y-108700D01*
G01X30650Y-92300D02*
X28130Y-91883D01*
X25925Y-90217D01*
X24035Y-87717D01*
X22775Y-84800D01*
X22145Y-81467D01*
Y-78133D01*
X22775Y-74800D01*
X24035Y-71883D01*
X25925Y-69384D01*
X28130Y-67717D01*
X30650Y-67300D01*
X33170Y-67717D01*
X35375Y-69384D01*
X37265Y-71883D01*
X38525Y-74800D01*
X39155Y-78133D01*
Y-81467D01*
X38525Y-84800D01*
X37265Y-87717D01*
X35375Y-90217D01*
X33170Y-91883D01*
X30650Y-92300D01*
G01X33170Y-85633D02*
X36950Y-92300D01*
G01X50495Y-75634D02*
Y-87300D01*
X51755Y-90217D01*
X53645Y-91883D01*
X55850Y-92300D01*
X58055Y-91883D01*
X59945Y-90217D01*
X61205Y-87300D01*
G01Y-92300D02*
Y-75634D01*
G01X86720Y-92300D02*
Y-75634D01*
G01Y-78550D02*
X85460Y-76884D01*
X83570Y-76050D01*
X81365Y-75634D01*
X79160Y-76467D01*
X77270Y-78133D01*
X76010Y-80634D01*
X75380Y-83967D01*
X76010Y-87300D01*
X77270Y-89801D01*
X79160Y-91467D01*
X81365Y-92300D01*
X83570Y-91883D01*
X85460Y-90634D01*
X86720Y-88967D01*
G01X100895Y-92300D02*
Y-75634D01*
G01Y-79800D02*
X102155Y-77717D01*
X104045Y-76050D01*
X106565Y-75634D01*
X108770Y-76050D01*
X110660Y-77717D01*
X111605Y-80634D01*
Y-92300D01*
G01X131450Y-67300D02*
Y-92300D01*
G01X127040Y-75634D02*
X135860D01*
G01X162320Y-92300D02*
Y-75634D01*
G01Y-78550D02*
X161060Y-76884D01*
X159170Y-76050D01*
X156965Y-75634D01*
X154760Y-76467D01*
X152870Y-78133D01*
X151610Y-80634D01*
X150980Y-83967D01*
X151610Y-87300D01*
X152870Y-89801D01*
X154760Y-91467D01*
X156965Y-92300D01*
X159170Y-91883D01*
X161060Y-90634D01*
X162320Y-88967D01*
G01X6548Y-105000D02*
Y-98700D01*
X10152Y-105000D01*
Y-98700D01*
G01X14650Y-105000D02*
X14023Y-104895D01*
X13475Y-104475D01*
X13005Y-103845D01*
X12692Y-103110D01*
X12535Y-102270D01*
Y-101430D01*
X12692Y-100590D01*
X13005Y-99855D01*
X13475Y-99225D01*
X14023Y-98805D01*
X14650Y-98700D01*
X15277Y-98805D01*
X15825Y-99225D01*
X16295Y-99855D01*
X16608Y-100590D01*
X16765Y-101430D01*
Y-102270D01*
X16608Y-103110D01*
X16295Y-103845D01*
X15825Y-104475D01*
X15277Y-104895D01*
X14650Y-105000D01*
G01X20950Y-105210D02*
X20793Y-105105D01*
Y-104895D01*
X20950Y-104790D01*
X21107Y-104895D01*
Y-105105D01*
X20950Y-105210D01*
G01X27250Y-105000D02*
Y-98700D01*
X26310Y-99960D01*
G01Y-105000D02*
X28190D01*
G01X33550D02*
X34098Y-104895D01*
X34725Y-104580D01*
X35117Y-104055D01*
X35273Y-103320D01*
X35117Y-102585D01*
X34647Y-101955D01*
X33942Y-101640D01*
X33158D01*
X32688Y-101430D01*
X32297Y-100905D01*
X32140Y-100170D01*
X32375Y-99435D01*
X32923Y-98910D01*
X33550Y-98700D01*
X34177Y-98910D01*
X34725Y-99435D01*
X34960Y-100170D01*
X34803Y-100905D01*
X34412Y-101430D01*
X33942Y-101640D01*
X33158D01*
X32453Y-101955D01*
X31983Y-102585D01*
X31827Y-103320D01*
X31983Y-104055D01*
X32375Y-104580D01*
X33002Y-104895D01*
X33550Y-105000D01*
G01X39850D02*
X40398Y-104895D01*
X41025Y-104580D01*
X41417Y-104055D01*
X41573Y-103320D01*
X41417Y-102585D01*
X40947Y-101955D01*
X40242Y-101640D01*
X39458D01*
X38988Y-101430D01*
X38597Y-100905D01*
X38440Y-100170D01*
X38675Y-99435D01*
X39223Y-98910D01*
X39850Y-98700D01*
X40477Y-98910D01*
X41025Y-99435D01*
X41260Y-100170D01*
X41103Y-100905D01*
X40712Y-101430D01*
X40242Y-101640D01*
X39458D01*
X38753Y-101955D01*
X38283Y-102585D01*
X38127Y-103320D01*
X38283Y-104055D01*
X38675Y-104580D01*
X39302Y-104895D01*
X39850Y-105000D01*
G01X45993Y-106155D02*
X46307Y-104790D01*
G01X50100Y-98700D02*
X51197Y-105000D01*
X52450Y-98700D01*
X53703Y-105000D01*
X54800Y-98700D01*
G01X60317Y-105000D02*
X57183D01*
Y-98700D01*
X60317D01*
G01X59063Y-101745D02*
X57183D01*
G01X63248Y-105000D02*
Y-98700D01*
X66852Y-105000D01*
Y-98700D01*
G01X76005Y-105000D02*
Y-98700D01*
G01X79295D02*
Y-105000D01*
G01Y-101850D02*
X76005D01*
G01X81600Y-98700D02*
X82697Y-105000D01*
X83950Y-98700D01*
X85203Y-105000D01*
X86300Y-98700D01*
G01X88292Y-105000D02*
X90250Y-98700D01*
X92208Y-105000D01*
G01X91503Y-102795D02*
X88997D01*
G01X101362Y-99750D02*
X101832Y-99120D01*
X102380Y-98805D01*
X103007Y-98700D01*
X103790Y-98910D01*
X104338Y-99435D01*
X104495Y-100065D01*
X104417Y-100695D01*
X104103Y-101220D01*
X102537Y-102270D01*
X101832Y-103005D01*
X101362Y-104055D01*
X101205Y-105000D01*
X104495D01*
G01X107348D02*
Y-98700D01*
X110952Y-105000D01*
Y-98700D01*
G01X113727Y-105000D02*
Y-98700D01*
X115293D01*
X115920Y-99015D01*
X116390Y-99435D01*
X116782Y-100065D01*
X117095Y-100800D01*
X117173Y-101850D01*
X117095Y-102900D01*
X116782Y-103635D01*
X116390Y-104265D01*
X115920Y-104685D01*
X115293Y-105000D01*
X113727D01*
G01X126483D02*
Y-98700D01*
X128442D01*
X129068Y-99015D01*
X129460Y-99435D01*
X129617Y-100275D01*
X129460Y-101115D01*
X128990Y-101640D01*
X128442Y-101955D01*
X126483D01*
G01X128442D02*
X129617Y-105000D01*
G01X132627D02*
Y-98700D01*
X134193D01*
X134820Y-99015D01*
X135290Y-99435D01*
X135682Y-100065D01*
X135995Y-100800D01*
X136073Y-101850D01*
X135995Y-102900D01*
X135682Y-103635D01*
X135290Y-104265D01*
X134820Y-104685D01*
X134193Y-105000D01*
X132627D01*
G01X140650Y-105210D02*
X140493Y-105105D01*
Y-104895D01*
X140650Y-104790D01*
X140807Y-104895D01*
Y-105105D01*
X140650Y-105210D01*
G01X33263Y821538D02*
X43217Y811584D01*
Y800319D01*
X77122Y766414D01*
Y562976D01*
X84282Y555816D01*
Y522828D01*
X34849Y473395D01*
Y455410D01*
X60084Y430175D01*
Y413211D01*
X53197Y406324D01*
X27245D01*
X17735Y415834D01*
G01X25389Y817601D02*
X34170D01*
X41817Y809954D01*
Y799739D01*
X75722Y765834D01*
Y562396D01*
X82882Y555236D01*
Y523408D01*
X33449Y473975D01*
Y454701D01*
X58414Y429736D01*
Y413651D01*
X52487Y407724D01*
X29632D01*
X22735Y414621D01*
Y425834D01*
G01X15547Y754608D02*
X18962Y751193D01*
X28854D01*
X32147Y754486D01*
X39476D01*
X54483Y739479D01*
Y679810D01*
G01X7673Y758545D02*
X27788D01*
X30912Y761669D01*
X35717D01*
X41905Y755481D01*
Y754088D01*
X59236Y736757D01*
Y670758D01*
G01X45056Y1817693D02*
X39510Y1823239D01*
X16406D01*
X10389Y1817222D01*
Y1764921D01*
X17082Y1758228D01*
Y1664717D01*
X75175Y1606624D01*
Y1562538D01*
X42938Y1530301D01*
Y1466497D01*
X46737Y1462698D01*
Y1365163D01*
X37482Y1355908D01*
Y1305217D01*
X33880Y1301615D01*
X31970D01*
X27920Y1297565D01*
X24102D01*
X18779Y1292242D01*
Y1284787D01*
X15551Y1281559D01*
Y1278228D01*
G01X45056Y1768087D02*
X53606Y1759537D01*
Y1645797D01*
X93146Y1606257D01*
Y1503574D01*
X53753Y1464181D01*
Y1359812D01*
X44877Y1350936D01*
Y1282897D01*
X40684Y1278704D01*
Y1267841D01*
X36056Y1263213D01*
X30661D01*
X27956Y1265918D01*
X24788D01*
X16415Y1274291D01*
X7677D01*
G01X23402Y1668874D02*
Y1662950D01*
X87546Y1598806D01*
Y1505894D01*
X48137Y1466485D01*
Y1362116D01*
X39277Y1353256D01*
Y1298768D01*
X34949Y1294440D01*
X32642D01*
X27840Y1289638D01*
X24600D01*
X20898Y1285936D01*
Y1278313D01*
X24890Y1274321D01*
X26372D01*
X30281Y1270412D01*
Y1269403D01*
X33267Y1266417D01*
G01X23402Y1718480D02*
X29331Y1712551D01*
Y1674803D01*
X23402Y1668874D01*
G01Y1768087D02*
X35097D01*
X50760Y1752424D01*
Y1644825D01*
X91746Y1603839D01*
Y1504154D01*
X52337Y1464745D01*
Y1360376D01*
X43477Y1351516D01*
Y1284501D01*
X33267Y1274291D01*
G01X23402Y1817693D02*
X16892Y1811183D01*
Y1767278D01*
X33520Y1750650D01*
Y1655738D01*
X88946Y1600312D01*
Y1505314D01*
X49537Y1465905D01*
Y1361536D01*
X40677Y1352676D01*
Y1292838D01*
X34440Y1286601D01*
X32027D01*
X29829Y1284403D01*
Y1282664D01*
X25393Y1278228D01*
G01X33263Y813664D02*
X35943Y810984D01*
Y810940D01*
X40417Y806466D01*
Y799159D01*
X74322Y765254D01*
Y561816D01*
X81482Y554656D01*
Y523988D01*
X32049Y474555D01*
Y453553D01*
X56701Y428901D01*
Y415201D01*
X50624Y409124D01*
X34445D01*
X27735Y415834D01*
G01X33263Y805790D02*
X37617Y801436D01*
Y797999D01*
X71522Y764094D01*
Y560656D01*
X78682Y553496D01*
Y525148D01*
X29249Y475715D01*
Y451237D01*
X37925Y442561D01*
Y423800D01*
X41968Y419757D01*
X43812D01*
X47735Y415834D01*
G01X25389Y801853D02*
X33913D01*
X36217Y799549D01*
Y797419D01*
X70122Y763514D01*
Y560076D01*
X77282Y552916D01*
Y525728D01*
X27849Y476295D01*
Y450527D01*
X36342Y442034D01*
Y422264D01*
X42539Y416067D01*
Y414968D01*
X45527Y411980D01*
X49745D01*
X52735Y414970D01*
Y425834D01*
G01X33263Y797915D02*
X68722Y762456D01*
Y559496D01*
X75882Y552336D01*
Y526308D01*
X26449Y476875D01*
Y449331D01*
X32735Y443045D01*
Y425834D01*
G01X25389Y809727D02*
X34092D01*
X39017Y804802D01*
Y798579D01*
X72922Y764674D01*
Y561236D01*
X80082Y554076D01*
Y524568D01*
X30649Y475135D01*
Y452847D01*
X42735Y440761D01*
Y425834D01*
G01X33263Y750671D02*
X33291Y750699D01*
X40644D01*
X52006Y739337D01*
Y677475D01*
X54154Y675327D01*
X57124D01*
G01X25389Y841223D02*
X28622Y837990D01*
Y828807D01*
X31470Y825959D01*
X36794D01*
X48583Y837748D01*
X78574D01*
X87339Y828983D01*
Y759905D01*
X95775Y751469D01*
G01X33263Y829412D02*
X58129Y854278D01*
X70865D01*
G01X45056Y1668874D02*
Y1647454D01*
X90346Y1602164D01*
Y1504734D01*
X50937Y1465325D01*
Y1360956D01*
X42077Y1352096D01*
Y1290975D01*
X33267Y1282165D01*
G01X119920Y1460197D02*
X115172Y1455449D01*
Y1448750D01*
X103152Y1436730D01*
Y1417871D01*
X87836Y1402555D01*
Y1274047D01*
X103270Y1258613D01*
Y1137732D01*
X85439Y1119901D01*
Y1101890D01*
X70315Y1086766D01*
Y999260D01*
X64404Y993349D01*
Y878739D01*
X70865Y872278D01*
G01Y866278D02*
X62559Y874584D01*
Y995088D01*
X68210Y1000739D01*
Y1091133D01*
X81863Y1104786D01*
Y1121445D01*
X101586Y1141168D01*
Y1255129D01*
X84486Y1272229D01*
Y1408702D01*
X92369Y1416585D01*
Y1491192D01*
X100683Y1499506D01*
Y1740953D01*
X103693Y1743963D01*
Y1794792D01*
X108125Y1799224D01*
X110916D01*
X119920Y1808228D01*
G01X139920Y1102165D02*
X135812Y1106273D01*
X115647D01*
X113365Y1108555D01*
X108032D01*
X104225Y1104748D01*
Y1064756D01*
X84005Y1044536D01*
Y938139D01*
X73940Y928074D01*
Y863353D01*
X70865Y860278D01*
G01X119920Y1112165D02*
X115070D01*
X113731Y1113504D01*
X106752D01*
X100971Y1107723D01*
Y1064463D01*
X82273Y1045765D01*
Y945367D01*
X66750Y929844D01*
Y894231D01*
X70865Y890116D01*
G01X114498Y396207D02*
Y370749D01*
X92644Y348895D01*
Y50589D01*
X101430Y41803D01*
G01X119920Y18071D02*
X110955Y27036D01*
Y40435D01*
X105779Y45611D01*
X101999D01*
X94137Y53473D01*
Y342655D01*
X117584Y366102D01*
X119920D01*
G01X104350Y62293D02*
X96057Y70586D01*
Y334556D01*
X126983Y365482D01*
Y397557D01*
X122481Y402059D01*
X110188D01*
X106725Y405522D01*
X106724D01*
X105451Y406795D01*
G01X92216Y899865D02*
Y882377D01*
X93139Y881454D01*
Y794543D01*
X119390Y768292D01*
X123565D01*
X127826Y764031D01*
Y712985D01*
X93615Y678774D01*
Y442611D01*
X115525Y420701D01*
Y414221D01*
X119263Y410483D01*
X122605D01*
X135472Y397616D01*
Y390550D01*
X139920Y386102D01*
G01X92633Y907404D02*
X94804Y905233D01*
Y802816D01*
X118285Y779335D01*
X122436D01*
X130259Y771512D01*
Y712889D01*
X95283Y677913D01*
Y444339D01*
X118359Y421263D01*
X142230D01*
X146241Y417252D01*
Y372423D01*
X139920Y366102D01*
G01X105451Y406795D02*
Y427293D01*
X91481Y441263D01*
Y679186D01*
X125981Y713686D01*
Y747127D01*
X123016Y750092D01*
X112789D01*
X108755Y754126D01*
X105087D01*
G01X119920Y714134D02*
X89817Y684031D01*
Y438980D01*
X99385Y429412D01*
Y410002D01*
X109163Y400224D01*
X122336D01*
X124709Y397851D01*
Y370891D01*
X119920Y366102D01*
G01Y714134D02*
X124240Y718454D01*
Y745471D01*
X121326Y748385D01*
X104831D01*
X88739Y764477D01*
Y870971D01*
X86037Y873673D01*
Y914199D01*
X92989Y921151D01*
Y927334D01*
G01X105087Y754126D02*
X90139Y769074D01*
Y872245D01*
X87635Y874749D01*
Y911477D01*
X95237Y919079D01*
Y929344D01*
X88606Y935975D01*
Y1016468D01*
X127913Y1055775D01*
Y1091526D01*
X121999Y1097440D01*
X115116D01*
X108779Y1103777D01*
Y1105760D01*
G01X98139Y990959D02*
X96890Y989710D01*
Y804972D01*
X113728Y788134D01*
X125217D01*
X132192Y781159D01*
Y721862D01*
X139920Y714134D01*
G01X90708Y878615D02*
X91539Y877784D01*
Y789581D01*
X104538Y776582D01*
Y773945D01*
X114349Y764134D01*
X119920D01*
G01Y1062165D02*
X86608Y1028853D01*
Y933715D01*
X92989Y927334D01*
G01X100719Y1324810D02*
X96501Y1329028D01*
Y1386778D01*
X119920Y1410197D01*
G01X95236Y1453321D02*
X102463Y1460548D01*
Y1733327D01*
X110293Y1741157D01*
Y1791558D01*
X107391Y1794460D01*
G01X139920Y38071D02*
X134762Y43229D01*
X115474D01*
X111588Y47115D01*
Y63662D01*
X98097Y77153D01*
Y331938D01*
X135472Y369313D01*
Y381654D01*
X139920Y386102D01*
G01Y18071D02*
X145989Y24140D01*
Y67659D01*
X140417Y73231D01*
X110894D01*
X101215Y82910D01*
Y330399D01*
X136918Y366102D01*
X139920D01*
G01X100687Y999391D02*
Y987137D01*
X98545Y984995D01*
Y806146D01*
X114557Y790134D01*
X125480D01*
X135004Y780610D01*
Y739050D01*
X139920Y734134D01*
G01X98139Y990959D02*
Y1020384D01*
X139920Y1062165D01*
G01Y1082165D02*
X145815Y1076270D01*
Y1061919D01*
X100687Y1016791D01*
Y999391D01*
G01X100719Y1306810D02*
X108017Y1314108D01*
Y1384008D01*
X127157Y1403148D01*
X145950D01*
X148998Y1406196D01*
Y1468374D01*
X141185Y1476187D01*
X116241D01*
X110281Y1482147D01*
Y1718634D01*
X146654Y1755007D01*
Y1795432D01*
X143858Y1798228D01*
X139920D01*
G01Y1410197D02*
X129259D01*
X104298Y1385236D01*
Y1334389D01*
X100719Y1330810D01*
G01Y1318810D02*
X106343Y1324434D01*
Y1384763D01*
X126187Y1404607D01*
X144565D01*
X147591Y1407633D01*
Y1442526D01*
X139920Y1450197D01*
G01X100719Y1336810D02*
X98179Y1339350D01*
Y1381759D01*
X134785Y1418365D01*
Y1422436D01*
X139920Y1427571D01*
Y1430197D01*
G01X119920Y1410197D02*
X126015Y1416292D01*
Y1459759D01*
X121496Y1464278D01*
X116701D01*
X104118Y1476861D01*
Y1732182D01*
X119920Y1747984D01*
Y1758228D01*
G01X139920Y1410197D02*
X145842Y1416119D01*
Y1432009D01*
X142371Y1435480D01*
X138108D01*
X134769Y1438819D01*
Y1461649D01*
X122004Y1474414D01*
X114429D01*
X107765Y1481078D01*
Y1726073D01*
X139920Y1758228D01*
G01Y1430197D02*
X130375Y1439742D01*
Y1458560D01*
X122806Y1466129D01*
X117764D01*
X106068Y1477825D01*
Y1730970D01*
X135648Y1760550D01*
Y1773956D01*
X139920Y1778228D01*
G01X202000Y-72000D02*
Y-80000D01*
X206000D01*
G01X213800D02*
Y-74667D01*
G01Y-75600D02*
X213400Y-75067D01*
X212800Y-74800D01*
X212100Y-74667D01*
X211400Y-74933D01*
X210800Y-75467D01*
X210400Y-76267D01*
X210200Y-77333D01*
X210400Y-78400D01*
X210800Y-79200D01*
X211400Y-79733D01*
X212100Y-80000D01*
X212800Y-79867D01*
X213400Y-79467D01*
X213800Y-78934D01*
G01X217900Y-82400D02*
X218500Y-82667D01*
X219300Y-82400D01*
X219800Y-81867D01*
X220200Y-81200D01*
X220800Y-79067D01*
X222100Y-74667D01*
G01X218900D02*
X220800Y-79067D01*
G01X226500Y-76400D02*
X229700D01*
X229400Y-75467D01*
X228900Y-74933D01*
X228200Y-74667D01*
X227500Y-74800D01*
X226900Y-75200D01*
X226500Y-76133D01*
X226300Y-76934D01*
Y-77733D01*
X226500Y-78533D01*
X227000Y-79333D01*
X227600Y-79867D01*
X228300Y-80000D01*
X229000Y-79733D01*
X229700Y-78934D01*
G01X234600Y-80000D02*
Y-74667D01*
G01Y-75733D02*
X235100Y-75200D01*
X235600Y-74800D01*
X236300Y-74667D01*
X236800Y-74800D01*
X237400Y-75200D01*
G01X223400Y-128934D02*
X224200Y-129600D01*
X225100Y-130000D01*
X225900D01*
X226700Y-129600D01*
X227300Y-128934D01*
X227600Y-128000D01*
X227400Y-127067D01*
X226900Y-126267D01*
X226000Y-125733D01*
X224800Y-125467D01*
X224100Y-124933D01*
X223800Y-124000D01*
X224000Y-123067D01*
X224500Y-122400D01*
X225200Y-122000D01*
X225900D01*
X226600Y-122267D01*
X227200Y-122933D01*
G01X235300Y-130000D02*
Y-124667D01*
G01Y-125600D02*
X234900Y-125067D01*
X234300Y-124800D01*
X233600Y-124667D01*
X232900Y-124933D01*
X232300Y-125467D01*
X231900Y-126267D01*
X231700Y-127333D01*
X231900Y-128400D01*
X232300Y-129200D01*
X232900Y-129733D01*
X233600Y-130000D01*
X234300Y-129867D01*
X234900Y-129467D01*
X235300Y-128934D01*
G01X239800Y-130000D02*
Y-124667D01*
G01Y-126000D02*
X240200Y-125333D01*
X240800Y-124800D01*
X241600Y-124667D01*
X242300Y-124800D01*
X242900Y-125333D01*
X243200Y-126267D01*
Y-130000D01*
G01X251300Y-122000D02*
Y-130000D01*
G01Y-128800D02*
X250900Y-129467D01*
X250300Y-129867D01*
X249600Y-130000D01*
X248800Y-129733D01*
X248200Y-129067D01*
X247800Y-128267D01*
X247700Y-127333D01*
X247800Y-126400D01*
X248200Y-125600D01*
X248800Y-124933D01*
X249600Y-124667D01*
X250300Y-124800D01*
X250800Y-125067D01*
X251300Y-125600D01*
G01X255400Y-132400D02*
X256000Y-132667D01*
X256800Y-132400D01*
X257300Y-131867D01*
X257700Y-131200D01*
X258300Y-129067D01*
X259600Y-124667D01*
G01X256400D02*
X258300Y-129067D01*
G01X226300Y-100733D02*
X226700Y-100333D01*
X227000Y-99667D01*
X227200Y-98733D01*
X227000Y-97933D01*
X226600Y-97400D01*
X225900Y-97000D01*
X223200D01*
Y-105000D01*
X226500D01*
X227200Y-104467D01*
X227600Y-103667D01*
X227800Y-102733D01*
X227600Y-101800D01*
X227000Y-101000D01*
X226300Y-100733D01*
X223200D01*
G01X233500Y-105000D02*
X232700Y-104867D01*
X232000Y-104333D01*
X231400Y-103533D01*
X231000Y-102600D01*
X230800Y-101533D01*
Y-100467D01*
X231000Y-99400D01*
X231400Y-98467D01*
X232000Y-97667D01*
X232700Y-97133D01*
X233500Y-97000D01*
X234300Y-97133D01*
X235000Y-97667D01*
X235600Y-98467D01*
X236000Y-99400D01*
X236200Y-100467D01*
Y-101533D01*
X236000Y-102600D01*
X235600Y-103533D01*
X235000Y-104333D01*
X234300Y-104867D01*
X233500Y-105000D01*
G01X241500Y-97000D02*
Y-105000D01*
G01X239200Y-97000D02*
X243800D01*
G01X249500D02*
Y-105000D01*
G01X247200Y-97000D02*
X251800D01*
G01X257500Y-105000D02*
X256700Y-104867D01*
X256000Y-104333D01*
X255400Y-103533D01*
X255000Y-102600D01*
X254800Y-101533D01*
Y-100467D01*
X255000Y-99400D01*
X255400Y-98467D01*
X256000Y-97667D01*
X256700Y-97133D01*
X257500Y-97000D01*
X258300Y-97133D01*
X259000Y-97667D01*
X259600Y-98467D01*
X260000Y-99400D01*
X260200Y-100467D01*
Y-101533D01*
X260000Y-102600D01*
X259600Y-103533D01*
X259000Y-104333D01*
X258300Y-104867D01*
X257500Y-105000D01*
G01X262900D02*
Y-97000D01*
X265500Y-103667D01*
X268100Y-97000D01*
Y-105000D01*
G01X255500Y-80000D02*
X256200Y-79867D01*
X257000Y-79467D01*
X257500Y-78800D01*
X257700Y-77867D01*
X257500Y-76934D01*
X256900Y-76133D01*
X256000Y-75733D01*
X255000D01*
X254400Y-75467D01*
X253900Y-74800D01*
X253700Y-73867D01*
X254000Y-72933D01*
X254700Y-72267D01*
X255500Y-72000D01*
X256300Y-72267D01*
X257000Y-72933D01*
X257300Y-73867D01*
X257100Y-74800D01*
X256600Y-75467D01*
X256000Y-75733D01*
X255000D01*
X254100Y-76133D01*
X253500Y-76934D01*
X253300Y-77867D01*
X253500Y-78800D01*
X254000Y-79467D01*
X254800Y-79867D01*
X255500Y-80000D01*
G01X328600Y-123333D02*
X329200Y-122533D01*
X329900Y-122133D01*
X330700Y-122000D01*
X331700Y-122267D01*
X332400Y-122933D01*
X332600Y-123733D01*
X332500Y-124534D01*
X332100Y-125200D01*
X330100Y-126533D01*
X329200Y-127467D01*
X328600Y-128800D01*
X328400Y-130000D01*
X332600D01*
G01X338500Y-122000D02*
X337700Y-122267D01*
X337100Y-122933D01*
X336700Y-123733D01*
X336400Y-124800D01*
X336300Y-126000D01*
X336400Y-127200D01*
X336700Y-128267D01*
X337100Y-129067D01*
X337700Y-129733D01*
X338500Y-130000D01*
X339300Y-129733D01*
X339900Y-129067D01*
X340300Y-128267D01*
X340600Y-127200D01*
X340700Y-126000D01*
X340600Y-124800D01*
X340300Y-123733D01*
X339900Y-122933D01*
X339300Y-122267D01*
X338500Y-122000D01*
G01X346500Y-130000D02*
Y-122000D01*
X345300Y-123600D01*
G01Y-130000D02*
X347700D01*
G01X352600Y-123333D02*
X353200Y-122533D01*
X353900Y-122133D01*
X354700Y-122000D01*
X355700Y-122267D01*
X356400Y-122933D01*
X356600Y-123733D01*
X356500Y-124534D01*
X356100Y-125200D01*
X354100Y-126533D01*
X353200Y-127467D01*
X352600Y-128800D01*
X352400Y-130000D01*
X356600D01*
G01X360700Y-130267D02*
X364300Y-122000D01*
G01X370500D02*
X369700Y-122267D01*
X369100Y-122933D01*
X368700Y-123733D01*
X368400Y-124800D01*
X368300Y-126000D01*
X368400Y-127200D01*
X368700Y-128267D01*
X369100Y-129067D01*
X369700Y-129733D01*
X370500Y-130000D01*
X371300Y-129733D01*
X371900Y-129067D01*
X372300Y-128267D01*
X372600Y-127200D01*
X372700Y-126000D01*
X372600Y-124800D01*
X372300Y-123733D01*
X371900Y-122933D01*
X371300Y-122267D01*
X370500Y-122000D01*
G01X376800Y-129067D02*
X377500Y-129733D01*
X378300Y-130000D01*
X379100Y-129733D01*
X379800Y-128934D01*
X380300Y-127733D01*
X380500Y-126533D01*
Y-125067D01*
X380300Y-123867D01*
X379800Y-122800D01*
X379200Y-122267D01*
X378500Y-122000D01*
X377700Y-122267D01*
X377100Y-122800D01*
X376700Y-123600D01*
X376500Y-124667D01*
X376700Y-125600D01*
X377200Y-126533D01*
X377800Y-127067D01*
X378500Y-127200D01*
X379300Y-126934D01*
X379900Y-126267D01*
X380500Y-125067D01*
G01X384700Y-130267D02*
X388300Y-122000D01*
G01X392600Y-123333D02*
X393200Y-122533D01*
X393900Y-122133D01*
X394700Y-122000D01*
X395700Y-122267D01*
X396400Y-122933D01*
X396600Y-123733D01*
X396500Y-124534D01*
X396100Y-125200D01*
X394100Y-126533D01*
X393200Y-127467D01*
X392600Y-128800D01*
X392400Y-130000D01*
X396600D01*
G01X402500D02*
X403200Y-129867D01*
X404000Y-129467D01*
X404500Y-128800D01*
X404700Y-127867D01*
X404500Y-126934D01*
X403900Y-126133D01*
X403000Y-125733D01*
X402000D01*
X401400Y-125467D01*
X400900Y-124800D01*
X400700Y-123867D01*
X401000Y-122933D01*
X401700Y-122267D01*
X402500Y-122000D01*
X403300Y-122267D01*
X404000Y-122933D01*
X404300Y-123867D01*
X404100Y-124800D01*
X403600Y-125467D01*
X403000Y-125733D01*
X402000D01*
X401100Y-126133D01*
X400500Y-126934D01*
X400300Y-127867D01*
X400500Y-128800D01*
X401000Y-129467D01*
X401800Y-129867D01*
X402500Y-130000D01*
G01X328300Y-105000D02*
Y-97000D01*
X330300D01*
X331100Y-97400D01*
X331700Y-97933D01*
X332200Y-98733D01*
X332600Y-99667D01*
X332700Y-101000D01*
X332600Y-102333D01*
X332200Y-103267D01*
X331700Y-104067D01*
X331100Y-104600D01*
X330300Y-105000D01*
X328300D01*
G01X336000D02*
X338500Y-97000D01*
X341000Y-105000D01*
G01X340100Y-102200D02*
X336900D01*
G01X346500Y-97000D02*
X345700Y-97267D01*
X345100Y-97933D01*
X344700Y-98733D01*
X344400Y-99800D01*
X344300Y-101000D01*
X344400Y-102200D01*
X344700Y-103267D01*
X345100Y-104067D01*
X345700Y-104733D01*
X346500Y-105000D01*
X347300Y-104733D01*
X347900Y-104067D01*
X348300Y-103267D01*
X348600Y-102200D01*
X348700Y-101000D01*
X348600Y-99800D01*
X348300Y-98733D01*
X347900Y-97933D01*
X347300Y-97267D01*
X346500Y-97000D01*
G01X354500D02*
Y-105000D01*
G01X352200Y-97000D02*
X356800D01*
G01X360600Y-101667D02*
X361300Y-100733D01*
X361900Y-100200D01*
X362700Y-99933D01*
X363400Y-100200D01*
X363900Y-100733D01*
X364300Y-101533D01*
X364400Y-102467D01*
X364300Y-103267D01*
X363900Y-104067D01*
X363300Y-104733D01*
X362600Y-105000D01*
X361800Y-104733D01*
X361100Y-103934D01*
X360700Y-102733D01*
X360600Y-101400D01*
X360800Y-99667D01*
X361100Y-98733D01*
X361600Y-97800D01*
X362300Y-97133D01*
X363000Y-97000D01*
X363700Y-97267D01*
X364200Y-97933D01*
G01X367900Y-105000D02*
Y-97000D01*
X370500Y-103667D01*
X373100Y-97000D01*
Y-105000D01*
G01X378500Y-97000D02*
Y-105000D01*
G01X376200Y-97000D02*
X380800D01*
G01X387300Y-100733D02*
X387700Y-100333D01*
X388000Y-99667D01*
X388200Y-98733D01*
X388000Y-97933D01*
X387600Y-97400D01*
X386900Y-97000D01*
X384200D01*
Y-105000D01*
X387500D01*
X388200Y-104467D01*
X388600Y-103667D01*
X388800Y-102733D01*
X388600Y-101800D01*
X388000Y-101000D01*
X387300Y-100733D01*
X384200D01*
G01X394500Y-105000D02*
X395200Y-104867D01*
X396000Y-104467D01*
X396500Y-103800D01*
X396700Y-102867D01*
X396500Y-101934D01*
X395900Y-101133D01*
X395000Y-100733D01*
X394000D01*
X393400Y-100467D01*
X392900Y-99800D01*
X392700Y-98867D01*
X393000Y-97933D01*
X393700Y-97267D01*
X394500Y-97000D01*
X395300Y-97267D01*
X396000Y-97933D01*
X396300Y-98867D01*
X396100Y-99800D01*
X395600Y-100467D01*
X395000Y-100733D01*
X394000D01*
X393100Y-101133D01*
X392500Y-101934D01*
X392300Y-102867D01*
X392500Y-103800D01*
X393000Y-104467D01*
X393800Y-104867D01*
X394500Y-105000D01*
G01X400300D02*
Y-97000D01*
X402300D01*
X403100Y-97400D01*
X403700Y-97933D01*
X404200Y-98733D01*
X404600Y-99667D01*
X404700Y-101000D01*
X404600Y-102333D01*
X404200Y-103267D01*
X403700Y-104067D01*
X403100Y-104600D01*
X402300Y-105000D01*
X400300D01*
G01X410500Y-97000D02*
X409700Y-97267D01*
X409100Y-97933D01*
X408700Y-98733D01*
X408400Y-99800D01*
X408300Y-101000D01*
X408400Y-102200D01*
X408700Y-103267D01*
X409100Y-104067D01*
X409700Y-104733D01*
X410500Y-105000D01*
X411300Y-104733D01*
X411900Y-104067D01*
X412300Y-103267D01*
X412600Y-102200D01*
X412700Y-101000D01*
X412600Y-99800D01*
X412300Y-98733D01*
X411900Y-97933D01*
X411300Y-97267D01*
X410500Y-97000D01*
G01X350500Y-72000D02*
Y-80000D01*
G01X348200Y-72000D02*
X352800D01*
G01X356600Y-76667D02*
X357300Y-75733D01*
X357900Y-75200D01*
X358700Y-74933D01*
X359400Y-75200D01*
X359900Y-75733D01*
X360300Y-76533D01*
X360400Y-77467D01*
X360300Y-78267D01*
X359900Y-79067D01*
X359300Y-79733D01*
X358600Y-80000D01*
X357800Y-79733D01*
X357100Y-78934D01*
X356700Y-77733D01*
X356600Y-76400D01*
X356800Y-74667D01*
X357100Y-73733D01*
X357600Y-72800D01*
X358300Y-72133D01*
X359000Y-72000D01*
X359700Y-72267D01*
X360200Y-72933D01*
G01X363900Y-80000D02*
Y-72000D01*
X366500Y-78667D01*
X369100Y-72000D01*
Y-80000D01*
G01X371500Y-82667D02*
X377500D01*
G01X380500Y-80000D02*
Y-72000D01*
X382900D01*
X383700Y-72400D01*
X384300Y-73333D01*
X384500Y-74400D01*
X384300Y-75467D01*
X383800Y-76267D01*
X382900Y-76667D01*
X380500D01*
G01X388300Y-80000D02*
Y-72000D01*
X390300D01*
X391100Y-72400D01*
X391700Y-72933D01*
X392200Y-73733D01*
X392600Y-74667D01*
X392700Y-76000D01*
X392600Y-77333D01*
X392200Y-78267D01*
X391700Y-79067D01*
X391100Y-79600D01*
X390300Y-80000D01*
X388300D01*
G01X399300Y-75733D02*
X399700Y-75333D01*
X400000Y-74667D01*
X400200Y-73733D01*
X400000Y-72933D01*
X399600Y-72400D01*
X398900Y-72000D01*
X396200D01*
Y-80000D01*
X399500D01*
X400200Y-79467D01*
X400600Y-78667D01*
X400800Y-77733D01*
X400600Y-76800D01*
X400000Y-76000D01*
X399300Y-75733D01*
X396200D01*
G01X403500Y-82667D02*
X409500D01*
G01X412300Y-80000D02*
Y-72000D01*
X414300D01*
X415100Y-72400D01*
X415700Y-72933D01*
X416200Y-73733D01*
X416600Y-74667D01*
X416700Y-76000D01*
X416600Y-77333D01*
X416200Y-78267D01*
X415700Y-79067D01*
X415100Y-79600D01*
X414300Y-80000D01*
X412300D01*
G01X419500Y-82667D02*
X425500D01*
G01X431300Y-75733D02*
X431700Y-75333D01*
X432000Y-74667D01*
X432200Y-73733D01*
X432000Y-72933D01*
X431600Y-72400D01*
X430900Y-72000D01*
X428200D01*
Y-80000D01*
X431500D01*
X432200Y-79467D01*
X432600Y-78667D01*
X432800Y-77733D01*
X432600Y-76800D01*
X432000Y-76000D01*
X431300Y-75733D01*
X428200D01*
G01X436300Y-80000D02*
Y-72000D01*
X438300D01*
X439100Y-72400D01*
X439700Y-72933D01*
X440200Y-73733D01*
X440600Y-74667D01*
X440700Y-76000D01*
X440600Y-77333D01*
X440200Y-78267D01*
X439700Y-79067D01*
X439100Y-79600D01*
X438300Y-80000D01*
X436300D01*
G01X443300Y-130000D02*
Y-122000D01*
X445300D01*
X446100Y-122400D01*
X446700Y-122933D01*
X447200Y-123733D01*
X447600Y-124667D01*
X447700Y-126000D01*
X447600Y-127333D01*
X447200Y-128267D01*
X446700Y-129067D01*
X446100Y-129600D01*
X445300Y-130000D01*
X443300D01*
G01X473000D02*
Y-122000D01*
X471800Y-123600D01*
G01Y-130000D02*
X474200D01*
G01X478800Y-128800D02*
X479400Y-129467D01*
X480100Y-129867D01*
X481000Y-130000D01*
X481900Y-129733D01*
X482600Y-129200D01*
X483100Y-128267D01*
X483200Y-127200D01*
X483000Y-126133D01*
X482500Y-125467D01*
X481800Y-124933D01*
X481100Y-124800D01*
X480400Y-124933D01*
X479500Y-125467D01*
X479800Y-122000D01*
X482500D01*
M02*
